(kicad_sch
	(version 20250114)
	(generator "eeschema")
	(generator_version "9.0")
	(paper "A3")
	(title_block
		(title "PolarFire SoM")
		(date "2025-07-22")
		(rev "1.1.4")
		(company "Antmicro Ltd")
		(comment 1 "www.antmicro.com")
	)
	(text "X"
		(exclude_from_sim no)
		(at 356.87 90.17 0)
		(effects
			(font
				(size 1.27 1.27)
			)
			(justify left bottom)
		)
	)
	(text "1V8"
		(exclude_from_sim no)
		(at 323.215 95.25 0)
		(effects
			(font
				(size 1.27 1.27)
			)
			(justify left bottom)
		)
	)
	(text "X"
		(exclude_from_sim no)
		(at 372.11 100.33 0)
		(effects
			(font
				(size 1.27 1.27)
			)
			(justify left bottom)
		)
	)
	(text "1	2	3	4	5	6	7	8	9	10	11	12"
		(exclude_from_sim no)
		(at 332.105 85.09 0)
		(effects
			(font
				(size 1.27 1.27)
			)
			(justify left bottom)
		)
	)
	(text "PG LED"
		(exclude_from_sim no)
		(at 336.55 125.73 0)
		(effects
			(font
				(size 4 4)
				(thickness 0.8)
				(bold yes)
			)
			(justify left bottom)
		)
	)
	(text "2V5_CL"
		(exclude_from_sim no)
		(at 321.945 100.33 0)
		(effects
			(font
				(size 1.27 1.27)
			)
			(justify left bottom)
		)
	)
	(text "GPIO Power Mux"
		(exclude_from_sim no)
		(at 13.97 178.435 0)
		(effects
			(font
				(size 4 4)
				(thickness 0.8)
				(bold yes)
			)
			(justify left bottom)
		)
	)
	(text "X"
		(exclude_from_sim no)
		(at 351.79 102.87 0)
		(effects
			(font
				(size 1.27 1.27)
			)
			(justify left bottom)
		)
	)
	(text "1V1"
		(exclude_from_sim no)
		(at 323.215 90.17 0)
		(effects
			(font
				(size 1.27 1.27)
			)
			(justify left bottom)
		)
	)
	(text "Core supply"
		(exclude_from_sim no)
		(at 125.095 179.07 0)
		(effects
			(font
				(size 4 4)
				(thickness 0.8)
				(bold yes)
			)
			(justify left bottom)
		)
	)
	(text "X"
		(exclude_from_sim no)
		(at 336.55 92.71 0)
		(effects
			(font
				(size 1.27 1.27)
			)
			(justify left bottom)
		)
	)
	(text "GLOBAL_EN"
		(exclude_from_sim no)
		(at 16.51 104.14 0)
		(effects
			(font
				(size 4 4)
				(thickness 0.8)
				(bold yes)
			)
			(justify left bottom)
		)
	)
	(text "X"
		(exclude_from_sim no)
		(at 361.95 105.41 0)
		(effects
			(font
				(size 1.27 1.27)
			)
			(justify left bottom)
		)
	)
	(text "Soft start delay time slot"
		(exclude_from_sim no)
		(at 344.17 82.55 0)
		(effects
			(font
				(size 1.27 1.27)
			)
			(justify left bottom)
		)
	)
	(text "X"
		(exclude_from_sim no)
		(at 341.63 87.63 0)
		(effects
			(font
				(size 1.27 1.27)
			)
			(justify left bottom)
		)
	)
	(text "X"
		(exclude_from_sim no)
		(at 346.71 95.25 0)
		(effects
			(font
				(size 1.27 1.27)
			)
			(justify left bottom)
		)
	)
	(text "I2C: 0x61"
		(exclude_from_sim no)
		(at 213.995 252.73 0)
		(effects
			(font
				(size 1.27 1.27)
			)
			(justify left bottom)
		)
	)
	(text "1V8_CL"
		(exclude_from_sim no)
		(at 321.31 105.41 0)
		(effects
			(font
				(size 1.27 1.27)
			)
			(justify left bottom)
		)
	)
	(text "X"
		(exclude_from_sim no)
		(at 367.03 97.79 0)
		(effects
			(font
				(size 1.27 1.27)
			)
			(justify left bottom)
		)
	)
	(text "VDDI_CL"
		(exclude_from_sim no)
		(at 321.31 102.87 0)
		(effects
			(font
				(size 1.27 1.27)
			)
			(justify left bottom)
		)
	)
	(text "Power Monitor"
		(exclude_from_sim no)
		(at 13.97 19.685 0)
		(effects
			(font
				(size 4 4)
				(thickness 0.8)
				(bold yes)
			)
			(justify left bottom)
		)
	)
	(text "3V3"
		(exclude_from_sim no)
		(at 323.215 87.63 0)
		(effects
			(font
				(size 1.27 1.27)
			)
			(justify left bottom)
		)
	)
	(text "1V2"
		(exclude_from_sim no)
		(at 323.215 97.79 0)
		(effects
			(font
				(size 1.27 1.27)
			)
			(justify left bottom)
		)
	)
	(text "PMIC"
		(exclude_from_sim no)
		(at 125.095 20.32 0)
		(effects
			(font
				(size 4 4)
				(thickness 0.8)
				(bold yes)
			)
			(justify left bottom)
		)
	)
	(text "2V5"
		(exclude_from_sim no)
		(at 323.215 92.71 0)
		(effects
			(font
				(size 1.27 1.27)
			)
			(justify left bottom)
		)
	)
	(junction
		(at 273.05 229.87)
		(diameter 0)
		(color 0 0 0 0)
	)
	(junction
		(at 261.62 60.96)
		(diameter 0)
		(color 0 0 0 0)
	)
	(junction
		(at 288.29 92.71)
		(diameter 0)
		(color 0 0 0 0)
	)
	(junction
		(at 278.13 127)
		(diameter 0)
		(color 0 0 0 0)
	)
	(junction
		(at 311.15 219.71)
		(diameter 0)
		(color 0 0 0 0)
	)
	(junction
		(at 182.88 68.58)
		(diameter 0)
		(color 0 0 0 0)
	)
	(junction
		(at 276.86 60.96)
		(diameter 0)
		(color 0 0 0 0)
	)
	(junction
		(at 290.83 240.03)
		(diameter 0)
		(color 0 0 0 0)
	)
	(junction
		(at 217.17 208.28)
		(diameter 0)
		(color 0 0 0 0)
	)
	(junction
		(at 243.84 219.71)
		(diameter 0)
		(color 0 0 0 0)
	)
	(junction
		(at 281.94 229.87)
		(diameter 0)
		(color 0 0 0 0)
	)
	(junction
		(at 198.12 218.44)
		(diameter 0)
		(color 0 0 0 0)
	)
	(junction
		(at 156.21 146.05)
		(diameter 0)
		(color 0 0 0 0)
	)
	(junction
		(at 262.89 127)
		(diameter 0)
		(color 0 0 0 0)
	)
	(junction
		(at 290.83 228.6)
		(diameter 0)
		(color 0 0 0 0)
	)
	(junction
		(at 160.02 134.62)
		(diameter 0)
		(color 0 0 0 0)
	)
	(junction
		(at 261.62 92.71)
		(diameter 0)
		(color 0 0 0 0)
	)
	(junction
		(at 63.5 135.89)
		(diameter 0)
		(color 0 0 0 0)
	)
	(junction
		(at 276.86 76.2)
		(diameter 0)
		(color 0 0 0 0)
	)
	(junction
		(at 198.12 208.28)
		(diameter 0)
		(color 0 0 0 0)
	)
	(junction
		(at 261.62 45.72)
		(diameter 0)
		(color 0 0 0 0)
	)
	(junction
		(at 262.89 143.51)
		(diameter 0)
		(color 0 0 0 0)
	)
	(junction
		(at 207.01 208.28)
		(diameter 0)
		(color 0 0 0 0)
	)
	(junction
		(at 200.66 68.58)
		(diameter 0)
		(color 0 0 0 0)
	)
	(junction
		(at 209.55 68.58)
		(diameter 0)
		(color 0 0 0 0)
	)
	(junction
		(at 209.55 114.3)
		(diameter 0)
		(color 0 0 0 0)
	)
	(junction
		(at 275.59 92.71)
		(diameter 0)
		(color 0 0 0 0)
	)
	(junction
		(at 262.89 76.2)
		(diameter 0)
		(color 0 0 0 0)
	)
	(junction
		(at 165.1 68.58)
		(diameter 0)
		(color 0 0 0 0)
	)
	(junction
		(at 91.44 213.36)
		(diameter 0)
		(color 0 0 0 0)
	)
	(junction
		(at 20.32 229.87)
		(diameter 0)
		(color 0 0 0 0)
	)
	(junction
		(at 290.83 219.71)
		(diameter 0)
		(color 0 0 0 0)
	)
	(junction
		(at 189.23 208.28)
		(diameter 0)
		(color 0 0 0 0)
	)
	(junction
		(at 256.54 60.96)
		(diameter 0)
		(color 0 0 0 0)
	)
	(junction
		(at 265.43 219.71)
		(diameter 0)
		(color 0 0 0 0)
	)
	(junction
		(at 295.91 60.96)
		(diameter 0)
		(color 0 0 0 0)
	)
	(junction
		(at 288.29 45.72)
		(diameter 0)
		(color 0 0 0 0)
	)
	(junction
		(at 276.86 45.72)
		(diameter 0)
		(color 0 0 0 0)
	)
	(junction
		(at 209.55 87.63)
		(diameter 0)
		(color 0 0 0 0)
	)
	(junction
		(at 62.23 243.84)
		(diameter 0)
		(color 0 0 0 0)
	)
	(junction
		(at 261.62 110.49)
		(diameter 0)
		(color 0 0 0 0)
	)
	(junction
		(at 62.23 210.82)
		(diameter 0)
		(color 0 0 0 0)
	)
	(junction
		(at 271.78 92.71)
		(diameter 0)
		(color 0 0 0 0)
	)
	(junction
		(at 295.91 92.71)
		(diameter 0)
		(color 0 0 0 0)
	)
	(junction
		(at 365.76 135.89)
		(diameter 0)
		(color 0 0 0 0)
	)
	(junction
		(at 273.05 219.71)
		(diameter 0)
		(color 0 0 0 0)
	)
	(junction
		(at 278.13 143.51)
		(diameter 0)
		(color 0 0 0 0)
	)
	(junction
		(at 160.02 129.54)
		(diameter 0)
		(color 0 0 0 0)
	)
	(junction
		(at 209.55 76.2)
		(diameter 0)
		(color 0 0 0 0)
	)
	(junction
		(at 257.81 92.71)
		(diameter 0)
		(color 0 0 0 0)
	)
	(junction
		(at 271.78 110.49)
		(diameter 0)
		(color 0 0 0 0)
	)
	(junction
		(at 173.99 68.58)
		(diameter 0)
		(color 0 0 0 0)
	)
	(junction
		(at 209.55 83.82)
		(diameter 0)
		(color 0 0 0 0)
	)
	(junction
		(at 288.29 110.49)
		(diameter 0)
		(color 0 0 0 0)
	)
	(junction
		(at 271.78 60.96)
		(diameter 0)
		(color 0 0 0 0)
	)
	(junction
		(at 256.54 45.72)
		(diameter 0)
		(color 0 0 0 0)
	)
	(junction
		(at 209.55 72.39)
		(diameter 0)
		(color 0 0 0 0)
	)
	(junction
		(at 275.59 110.49)
		(diameter 0)
		(color 0 0 0 0)
	)
	(junction
		(at 172.72 151.13)
		(diameter 0)
		(color 0 0 0 0)
	)
	(junction
		(at 354.33 144.78)
		(diameter 0)
		(color 0 0 0 0)
	)
	(junction
		(at 209.55 80.01)
		(diameter 0)
		(color 0 0 0 0)
	)
	(junction
		(at 295.91 110.49)
		(diameter 0)
		(color 0 0 0 0)
	)
	(junction
		(at 270.51 45.72)
		(diameter 0)
		(color 0 0 0 0)
	)
	(junction
		(at 288.29 60.96)
		(diameter 0)
		(color 0 0 0 0)
	)
	(junction
		(at 295.91 45.72)
		(diameter 0)
		(color 0 0 0 0)
	)
	(junction
		(at 88.9 205.74)
		(diameter 0)
		(color 0 0 0 0)
	)
	(junction
		(at 195.58 92.71)
		(diameter 0)
		(color 0 0 0 0)
	)
	(junction
		(at 231.14 248.92)
		(diameter 0)
		(color 0 0 0 0)
	)
	(junction
		(at 191.77 68.58)
		(diameter 0)
		(color 0 0 0 0)
	)
	(junction
		(at 365.76 152.4)
		(diameter 0)
		(color 0 0 0 0)
	)
	(junction
		(at 257.81 110.49)
		(diameter 0)
		(color 0 0 0 0)
	)
	(junction
		(at 189.23 218.44)
		(diameter 0)
		(color 0 0 0 0)
	)
	(junction
		(at 281.94 219.71)
		(diameter 0)
		(color 0 0 0 0)
	)
	(junction
		(at 265.43 229.87)
		(diameter 0)
		(color 0 0 0 0)
	)
	(junction
		(at 256.54 219.71)
		(diameter 0)
		(color 0 0 0 0)
	)
	(no_connect
		(at 237.49 114.3)
	)
	(no_connect
		(at 82.55 246.38)
	)
	(bus_entry
		(at 194.31 107.95)
		(size 2.54 -2.54)
		(stroke
			(width 0)
			(type default)
		)
	)
	(bus_entry
		(at 196.85 242.57)
		(size 2.54 -2.54)
		(stroke
			(width 0)
			(type default)
		)
	)
	(bus_entry
		(at 194.31 110.49)
		(size 2.54 -2.54)
		(stroke
			(width 0)
			(type default)
		)
	)
	(bus_entry
		(at 196.85 240.03)
		(size 2.54 -2.54)
		(stroke
			(width 0)
			(type default)
		)
	)
	(bus_entry
		(at 43.18 54.61)
		(size 2.54 2.54)
		(stroke
			(width 0)
			(type default)
		)
	)
	(bus_entry
		(at 43.18 52.07)
		(size 2.54 2.54)
		(stroke
			(width 0)
			(type default)
		)
	)
	(wire
		(pts
			(xy 209.55 87.63) (xy 212.09 87.63)
		)
		(stroke
			(width 0)
			(type default)
		)
	)
	(wire
		(pts
			(xy 261.62 60.96) (xy 261.62 62.23)
		)
		(stroke
			(width 0)
			(type default)
		)
	)
	(wire
		(pts
			(xy 295.91 60.96) (xy 299.72 60.96)
		)
		(stroke
			(width 0)
			(type default)
		)
	)
	(wire
		(pts
			(xy 241.3 127) (xy 262.89 127)
		)
		(stroke
			(width 0)
			(type default)
		)
	)
	(wire
		(pts
			(xy 295.91 92.71) (xy 295.91 99.06)
		)
		(stroke
			(width 0)
			(type default)
		)
	)
	(polyline
		(pts
			(xy 375.92 82.55) (xy 375.92 95.25)
		)
		(stroke
			(width 0)
			(type default)
		)
	)
	(wire
		(pts
			(xy 102.87 59.69) (xy 115.57 59.69)
		)
		(stroke
			(width 0)
			(type default)
		)
	)
	(wire
		(pts
			(xy 198.12 218.44) (xy 189.23 218.44)
		)
		(stroke
			(width 0)
			(type default)
		)
	)
	(wire
		(pts
			(xy 33.02 53.34) (xy 33.02 54.61)
		)
		(stroke
			(width 0)
			(type default)
		)
	)
	(wire
		(pts
			(xy 281.94 214.63) (xy 281.94 219.71)
		)
		(stroke
			(width 0)
			(type default)
		)
	)
	(wire
		(pts
			(xy 102.87 49.53) (xy 115.57 49.53)
		)
		(stroke
			(width 0)
			(type default)
		)
	)
	(wire
		(pts
			(xy 265.43 229.87) (xy 273.05 229.87)
		)
		(stroke
			(width 0)
			(type default)
		)
	)
	(wire
		(pts
			(xy 256.54 92.71) (xy 257.81 92.71)
		)
		(stroke
			(width 0)
			(type default)
		)
	)
	(wire
		(pts
			(xy 209.55 72.39) (xy 212.09 72.39)
		)
		(stroke
			(width 0)
			(type default)
		)
	)
	(wire
		(pts
			(xy 288.29 92.71) (xy 288.29 99.06)
		)
		(stroke
			(width 0)
			(type default)
		)
	)
	(wire
		(pts
			(xy 62.23 209.55) (xy 62.23 210.82)
		)
		(stroke
			(width 0)
			(type default)
		)
	)
	(wire
		(pts
			(xy 248.92 92.71) (xy 251.46 92.71)
		)
		(stroke
			(width 0)
			(type default)
		)
	)
	(wire
		(pts
			(xy 279.4 132.08) (xy 278.13 132.08)
		)
		(stroke
			(width 0)
			(type default)
		)
	)
	(bus
		(pts
			(xy 41.91 40.64) (xy 43.18 41.91)
		)
		(stroke
			(width 0)
			(type default)
		)
	)
	(wire
		(pts
			(xy 64.77 246.38) (xy 62.23 246.38)
		)
		(stroke
			(width 0)
			(type default)
		)
	)
	(wire
		(pts
			(xy 257.81 92.71) (xy 261.62 92.71)
		)
		(stroke
			(width 0)
			(type default)
		)
	)
	(wire
		(pts
			(xy 189.23 215.9) (xy 189.23 218.44)
		)
		(stroke
			(width 0)
			(type default)
		)
	)
	(wire
		(pts
			(xy 273.05 229.87) (xy 281.94 229.87)
		)
		(stroke
			(width 0)
			(type default)
		)
	)
	(wire
		(pts
			(xy 246.38 110.49) (xy 251.46 110.49)
		)
		(stroke
			(width 0)
			(type default)
		)
	)
	(wire
		(pts
			(xy 248.92 76.2) (xy 262.89 76.2)
		)
		(stroke
			(width 0)
			(type default)
		)
	)
	(wire
		(pts
			(xy 20.32 237.49) (xy 20.32 236.22)
		)
		(stroke
			(width 0)
			(type default)
		)
	)
	(polyline
		(pts
			(xy 355.6 82.55) (xy 355.6 95.25)
		)
		(stroke
			(width 0)
			(type default)
		)
	)
	(wire
		(pts
			(xy 160.02 129.54) (xy 176.53 129.54)
		)
		(stroke
			(width 0)
			(type default)
		)
	)
	(wire
		(pts
			(xy 354.33 152.4) (xy 354.33 151.13)
		)
		(stroke
			(width 0)
			(type default)
		)
	)
	(wire
		(pts
			(xy 158.75 137.16) (xy 160.02 137.16)
		)
		(stroke
			(width 0)
			(type default)
		)
	)
	(wire
		(pts
			(xy 86.36 205.74) (xy 88.9 205.74)
		)
		(stroke
			(width 0)
			(type default)
		)
	)
	(wire
		(pts
			(xy 229.87 248.92) (xy 231.14 248.92)
		)
		(stroke
			(width 0)
			(type default)
		)
	)
	(wire
		(pts
			(xy 82.55 213.36) (xy 91.44 213.36)
		)
		(stroke
			(width 0)
			(type default)
		)
	)
	(wire
		(pts
			(xy 241.3 219.71) (xy 243.84 219.71)
		)
		(stroke
			(width 0)
			(type default)
		)
	)
	(wire
		(pts
			(xy 60.96 59.69) (xy 66.04 59.69)
		)
		(stroke
			(width 0)
			(type default)
		)
	)
	(wire
		(pts
			(xy 262.89 143.51) (xy 278.13 143.51)
		)
		(stroke
			(width 0)
			(type default)
		)
	)
	(polyline
		(pts
			(xy 360.68 82.55) (xy 360.68 95.25)
		)
		(stroke
			(width 0)
			(type default)
		)
	)
	(wire
		(pts
			(xy 62.23 246.38) (xy 62.23 243.84)
		)
		(stroke
			(width 0)
			(type default)
		)
	)
	(wire
		(pts
			(xy 217.17 208.28) (xy 217.17 219.71)
		)
		(stroke
			(width 0)
			(type default)
		)
	)
	(wire
		(pts
			(xy 160.02 134.62) (xy 176.53 134.62)
		)
		(stroke
			(width 0)
			(type default)
		)
	)
	(polyline
		(pts
			(xy 335.28 87.63) (xy 335.28 105.41)
		)
		(stroke
			(width 0)
			(type default)
		)
	)
	(wire
		(pts
			(xy 290.83 219.71) (xy 290.83 228.6)
		)
		(stroke
			(width 0)
			(type default)
		)
	)
	(wire
		(pts
			(xy 290.83 219.71) (xy 293.37 219.71)
		)
		(stroke
			(width 0)
			(type default)
		)
	)
	(wire
		(pts
			(xy 199.39 240.03) (xy 220.98 240.03)
		)
		(stroke
			(width 0)
			(type default)
		)
	)
	(wire
		(pts
			(xy 261.62 60.96) (xy 271.78 60.96)
		)
		(stroke
			(width 0)
			(type default)
		)
	)
	(wire
		(pts
			(xy 302.26 237.49) (xy 302.26 240.03)
		)
		(stroke
			(width 0)
			(type default)
		)
	)
	(bus
		(pts
			(xy 196.85 242.57) (xy 196.85 240.03)
		)
		(stroke
			(width 0)
			(type default)
		)
	)
	(wire
		(pts
			(xy 198.12 218.44) (xy 207.01 218.44)
		)
		(stroke
			(width 0)
			(type default)
		)
	)
	(wire
		(pts
			(xy 281.94 229.87) (xy 281.94 231.14)
		)
		(stroke
			(width 0)
			(type default)
		)
	)
	(wire
		(pts
			(xy 82.55 210.82) (xy 86.36 210.82)
		)
		(stroke
			(width 0)
			(type default)
		)
	)
	(wire
		(pts
			(xy 195.58 92.71) (xy 195.58 93.98)
		)
		(stroke
			(width 0)
			(type default)
		)
	)
	(polyline
		(pts
			(xy 321.31 95.25) (xy 391.16 95.25)
		)
		(stroke
			(width 0)
			(type default)
		)
	)
	(wire
		(pts
			(xy 102.87 64.77) (xy 115.57 64.77)
		)
		(stroke
			(width 0)
			(type default)
		)
	)
	(bus
		(pts
			(xy 193.04 120.65) (xy 194.31 119.38)
		)
		(stroke
			(width 0)
			(type default)
		)
	)
	(wire
		(pts
			(xy 93.98 49.53) (xy 97.79 49.53)
		)
		(stroke
			(width 0)
			(type default)
		)
	)
	(wire
		(pts
			(xy 238.76 45.72) (xy 248.92 45.72)
		)
		(stroke
			(width 0)
			(type default)
		)
	)
	(wire
		(pts
			(xy 191.77 68.58) (xy 191.77 69.85)
		)
		(stroke
			(width 0)
			(type default)
		)
	)
	(wire
		(pts
			(xy 50.8 62.23) (xy 55.88 62.23)
		)
		(stroke
			(width 0)
			(type default)
		)
	)
	(wire
		(pts
			(xy 261.62 110.49) (xy 257.81 110.49)
		)
		(stroke
			(width 0)
			(type default)
		)
	)
	(wire
		(pts
			(xy 93.98 67.31) (xy 115.57 67.31)
		)
		(stroke
			(width 0)
			(type default)
		)
	)
	(wire
		(pts
			(xy 295.91 116.84) (xy 295.91 110.49)
		)
		(stroke
			(width 0)
			(type default)
		)
	)
	(wire
		(pts
			(xy 288.29 45.72) (xy 288.29 52.07)
		)
		(stroke
			(width 0)
			(type default)
		)
	)
	(wire
		(pts
			(xy 63.5 133.35) (xy 63.5 135.89)
		)
		(stroke
			(width 0)
			(type default)
		)
	)
	(wire
		(pts
			(xy 254 45.72) (xy 256.54 45.72)
		)
		(stroke
			(width 0)
			(type default)
		)
	)
	(wire
		(pts
			(xy 196.85 107.95) (xy 212.09 107.95)
		)
		(stroke
			(width 0)
			(type default)
		)
	)
	(polyline
		(pts
			(xy 330.2 88.9) (xy 330.2 105.41)
		)
		(stroke
			(width 0)
			(type default)
		)
	)
	(wire
		(pts
			(xy 57.15 215.9) (xy 64.77 215.9)
		)
		(stroke
			(width 0)
			(type default)
		)
	)
	(wire
		(pts
			(xy 207.01 215.9) (xy 207.01 218.44)
		)
		(stroke
			(width 0)
			(type default)
		)
	)
	(wire
		(pts
			(xy 55.88 71.12) (xy 55.88 72.39)
		)
		(stroke
			(width 0)
			(type default)
		)
	)
	(wire
		(pts
			(xy 261.62 116.84) (xy 261.62 118.11)
		)
		(stroke
			(width 0)
			(type default)
		)
	)
	(wire
		(pts
			(xy 246.38 91.44) (xy 246.38 95.25)
		)
		(stroke
			(width 0)
			(type default)
		)
	)
	(wire
		(pts
			(xy 273.05 219.71) (xy 273.05 222.25)
		)
		(stroke
			(width 0)
			(type default)
		)
	)
	(wire
		(pts
			(xy 53.34 251.46) (xy 64.77 251.46)
		)
		(stroke
			(width 0)
			(type default)
		)
	)
	(wire
		(pts
			(xy 265.43 219.71) (xy 273.05 219.71)
		)
		(stroke
			(width 0)
			(type default)
		)
	)
	(wire
		(pts
			(xy 271.78 99.06) (xy 271.78 100.33)
		)
		(stroke
			(width 0)
			(type default)
		)
	)
	(wire
		(pts
			(xy 209.55 72.39) (xy 209.55 76.2)
		)
		(stroke
			(width 0)
			(type default)
		)
	)
	(wire
		(pts
			(xy 191.77 74.93) (xy 191.77 76.2)
		)
		(stroke
			(width 0)
			(type default)
		)
	)
	(wire
		(pts
			(xy 276.86 73.66) (xy 276.86 76.2)
		)
		(stroke
			(width 0)
			(type default)
		)
	)
	(wire
		(pts
			(xy 240.03 205.74) (xy 243.84 205.74)
		)
		(stroke
			(width 0)
			(type default)
		)
	)
	(wire
		(pts
			(xy 261.62 45.72) (xy 270.51 45.72)
		)
		(stroke
			(width 0)
			(type default)
		)
	)
	(wire
		(pts
			(xy 53.34 217.17) (xy 53.34 218.44)
		)
		(stroke
			(width 0)
			(type default)
		)
	)
	(wire
		(pts
			(xy 212.09 111.76) (xy 209.55 111.76)
		)
		(stroke
			(width 0)
			(type default)
		)
	)
	(wire
		(pts
			(xy 365.76 152.4) (xy 365.76 153.67)
		)
		(stroke
			(width 0)
			(type default)
		)
	)
	(wire
		(pts
			(xy 237.49 88.9) (xy 248.92 88.9)
		)
		(stroke
			(width 0)
			(type default)
		)
	)
	(wire
		(pts
			(xy 278.13 58.42) (xy 276.86 58.42)
		)
		(stroke
			(width 0)
			(type default)
		)
	)
	(wire
		(pts
			(xy 246.38 63.5) (xy 256.54 63.5)
		)
		(stroke
			(width 0)
			(type default)
		)
	)
	(wire
		(pts
			(xy 262.89 82.55) (xy 262.89 83.82)
		)
		(stroke
			(width 0)
			(type default)
		)
	)
	(wire
		(pts
			(xy 243.84 205.74) (xy 243.84 219.71)
		)
		(stroke
			(width 0)
			(type default)
		)
	)
	(wire
		(pts
			(xy 288.29 99.06) (xy 278.13 99.06)
		)
		(stroke
			(width 0)
			(type default)
		)
	)
	(wire
		(pts
			(xy 45.72 57.15) (xy 66.04 57.15)
		)
		(stroke
			(width 0)
			(type default)
		)
	)
	(wire
		(pts
			(xy 262.89 143.51) (xy 262.89 146.05)
		)
		(stroke
			(width 0)
			(type default)
		)
	)
	(wire
		(pts
			(xy 57.15 248.92) (xy 64.77 248.92)
		)
		(stroke
			(width 0)
			(type default)
		)
	)
	(wire
		(pts
			(xy 53.34 250.19) (xy 53.34 251.46)
		)
		(stroke
			(width 0)
			(type default)
		)
	)
	(wire
		(pts
			(xy 299.72 92.71) (xy 299.72 91.44)
		)
		(stroke
			(width 0)
			(type default)
		)
	)
	(wire
		(pts
			(xy 354.33 152.4) (xy 365.76 152.4)
		)
		(stroke
			(width 0)
			(type default)
		)
	)
	(wire
		(pts
			(xy 288.29 67.31) (xy 278.13 67.31)
		)
		(stroke
			(width 0)
			(type default)
		)
	)
	(wire
		(pts
			(xy 59.69 52.07) (xy 66.04 52.07)
		)
		(stroke
			(width 0)
			(type default)
		)
	)
	(wire
		(pts
			(xy 271.78 92.71) (xy 275.59 92.71)
		)
		(stroke
			(width 0)
			(type default)
		)
	)
	(polyline
		(pts
			(xy 360.68 92.71) (xy 360.68 105.41)
		)
		(stroke
			(width 0)
			(type default)
		)
	)
	(wire
		(pts
			(xy 209.55 114.3) (xy 212.09 114.3)
		)
		(stroke
			(width 0)
			(type default)
		)
	)
	(polyline
		(pts
			(xy 345.44 87.63) (xy 345.44 105.41)
		)
		(stroke
			(width 0)
			(type default)
		)
	)
	(wire
		(pts
			(xy 256.54 219.71) (xy 265.43 219.71)
		)
		(stroke
			(width 0)
			(type default)
		)
	)
	(wire
		(pts
			(xy 156.21 146.05) (xy 156.21 148.59)
		)
		(stroke
			(width 0)
			(type default)
		)
	)
	(wire
		(pts
			(xy 270.51 45.72) (xy 270.51 46.99)
		)
		(stroke
			(width 0)
			(type default)
		)
	)
	(wire
		(pts
			(xy 199.39 237.49) (xy 220.98 237.49)
		)
		(stroke
			(width 0)
			(type default)
		)
	)
	(wire
		(pts
			(xy 200.66 68.58) (xy 209.55 68.58)
		)
		(stroke
			(width 0)
			(type default)
		)
	)
	(wire
		(pts
			(xy 241.3 71.12) (xy 241.3 48.26)
		)
		(stroke
			(width 0)
			(type default)
		)
	)
	(wire
		(pts
			(xy 271.78 60.96) (xy 271.78 62.23)
		)
		(stroke
			(width 0)
			(type default)
		)
	)
	(wire
		(pts
			(xy 209.55 114.3) (xy 209.55 115.57)
		)
		(stroke
			(width 0)
			(type default)
		)
	)
	(wire
		(pts
			(xy 237.49 96.52) (xy 246.38 96.52)
		)
		(stroke
			(width 0)
			(type default)
		)
	)
	(wire
		(pts
			(xy 270.51 45.72) (xy 276.86 45.72)
		)
		(stroke
			(width 0)
			(type default)
		)
	)
	(wire
		(pts
			(xy 278.13 143.51) (xy 278.13 148.59)
		)
		(stroke
			(width 0)
			(type default)
		)
	)
	(wire
		(pts
			(xy 295.91 116.84) (xy 306.07 116.84)
		)
		(stroke
			(width 0)
			(type default)
		)
	)
	(wire
		(pts
			(xy 63.5 135.89) (xy 63.5 138.43)
		)
		(stroke
			(width 0)
			(type default)
		)
	)
	(wire
		(pts
			(xy 63.5 135.89) (xy 69.85 135.89)
		)
		(stroke
			(width 0)
			(type default)
		)
	)
	(polyline
		(pts
			(xy 321.31 85.09) (xy 391.16 85.09)
		)
		(stroke
			(width 0)
			(type default)
		)
	)
	(polyline
		(pts
			(xy 321.31 90.17) (xy 321.31 95.25)
		)
		(stroke
			(width 0)
			(type default)
		)
	)
	(wire
		(pts
			(xy 82.55 243.84) (xy 88.9 243.84)
		)
		(stroke
			(width 0)
			(type default)
		)
	)
	(wire
		(pts
			(xy 88.9 196.85) (xy 88.9 198.12)
		)
		(stroke
			(width 0)
			(type default)
		)
	)
	(wire
		(pts
			(xy 365.76 135.89) (xy 365.76 137.16)
		)
		(stroke
			(width 0)
			(type default)
		)
	)
	(wire
		(pts
			(xy 243.84 76.2) (xy 243.84 60.96)
		)
		(stroke
			(width 0)
			(type default)
		)
	)
	(wire
		(pts
			(xy 294.64 110.49) (xy 295.91 110.49)
		)
		(stroke
			(width 0)
			(type default)
		)
	)
	(wire
		(pts
			(xy 209.55 76.2) (xy 212.09 76.2)
		)
		(stroke
			(width 0)
			(type default)
		)
	)
	(wire
		(pts
			(xy 209.55 111.76) (xy 209.55 114.3)
		)
		(stroke
			(width 0)
			(type default)
		)
	)
	(wire
		(pts
			(xy 354.33 144.78) (xy 354.33 146.05)
		)
		(stroke
			(width 0)
			(type default)
		)
	)
	(wire
		(pts
			(xy 290.83 237.49) (xy 290.83 240.03)
		)
		(stroke
			(width 0)
			(type default)
		)
	)
	(wire
		(pts
			(xy 262.89 127) (xy 278.13 127)
		)
		(stroke
			(width 0)
			(type default)
		)
	)
	(wire
		(pts
			(xy 212.09 96.52) (xy 204.47 96.52)
		)
		(stroke
			(width 0)
			(type default)
		)
	)
	(wire
		(pts
			(xy 257.81 110.49) (xy 257.81 113.03)
		)
		(stroke
			(width 0)
			(type default)
		)
	)
	(wire
		(pts
			(xy 186.69 87.63) (xy 209.55 87.63)
		)
		(stroke
			(width 0)
			(type default)
		)
	)
	(polyline
		(pts
			(xy 321.31 80.01) (xy 321.31 90.17)
		)
		(stroke
			(width 0)
			(type default)
		)
	)
	(wire
		(pts
			(xy 160.02 137.16) (xy 160.02 134.62)
		)
		(stroke
			(width 0)
			(type default)
		)
	)
	(wire
		(pts
			(xy 193.04 92.71) (xy 195.58 92.71)
		)
		(stroke
			(width 0)
			(type default)
		)
	)
	(wire
		(pts
			(xy 246.38 95.25) (xy 257.81 95.25)
		)
		(stroke
			(width 0)
			(type default)
		)
	)
	(wire
		(pts
			(xy 276.86 58.42) (xy 276.86 60.96)
		)
		(stroke
			(width 0)
			(type default)
		)
	)
	(wire
		(pts
			(xy 294.64 60.96) (xy 295.91 60.96)
		)
		(stroke
			(width 0)
			(type default)
		)
	)
	(wire
		(pts
			(xy 91.44 207.01) (xy 91.44 205.74)
		)
		(stroke
			(width 0)
			(type default)
		)
	)
	(wire
		(pts
			(xy 256.54 229.87) (xy 265.43 229.87)
		)
		(stroke
			(width 0)
			(type default)
		)
	)
	(polyline
		(pts
			(xy 345.44 82.55) (xy 345.44 95.25)
		)
		(stroke
			(width 0)
			(type default)
		)
	)
	(wire
		(pts
			(xy 20.32 228.6) (xy 20.32 229.87)
		)
		(stroke
			(width 0)
			(type default)
		)
	)
	(bus
		(pts
			(xy 194.31 107.95) (xy 194.31 110.49)
		)
		(stroke
			(width 0)
			(type default)
		)
	)
	(wire
		(pts
			(xy 365.76 135.89) (xy 370.84 135.89)
		)
		(stroke
			(width 0)
			(type default)
		)
	)
	(wire
		(pts
			(xy 85.09 218.44) (xy 85.09 219.71)
		)
		(stroke
			(width 0)
			(type default)
		)
	)
	(wire
		(pts
			(xy 276.86 76.2) (xy 289.56 76.2)
		)
		(stroke
			(width 0)
			(type default)
		)
	)
	(wire
		(pts
			(xy 262.89 151.13) (xy 262.89 152.4)
		)
		(stroke
			(width 0)
			(type default)
		)
	)
	(wire
		(pts
			(xy 91.44 212.09) (xy 91.44 213.36)
		)
		(stroke
			(width 0)
			(type default)
		)
	)
	(wire
		(pts
			(xy 59.69 50.8) (xy 59.69 52.07)
		)
		(stroke
			(width 0)
			(type default)
		)
	)
	(wire
		(pts
			(xy 63.5 67.31) (xy 66.04 67.31)
		)
		(stroke
			(width 0)
			(type default)
		)
	)
	(wire
		(pts
			(xy 24.13 59.69) (xy 24.13 60.96)
		)
		(stroke
			(width 0)
			(type default)
		)
	)
	(wire
		(pts
			(xy 24.13 53.34) (xy 24.13 54.61)
		)
		(stroke
			(width 0)
			(type default)
		)
	)
	(polyline
		(pts
			(xy 370.84 92.71) (xy 370.84 105.41)
		)
		(stroke
			(width 0)
			(type default)
		)
	)
	(wire
		(pts
			(xy 256.54 60.96) (xy 256.54 63.5)
		)
		(stroke
			(width 0)
			(type default)
		)
	)
	(polyline
		(pts
			(xy 381 92.71) (xy 381 105.41)
		)
		(stroke
			(width 0)
			(type default)
		)
	)
	(wire
		(pts
			(xy 271.78 92.71) (xy 271.78 93.98)
		)
		(stroke
			(width 0)
			(type default)
		)
	)
	(wire
		(pts
			(xy 232.41 247.65) (xy 232.41 248.92)
		)
		(stroke
			(width 0)
			(type default)
		)
	)
	(wire
		(pts
			(xy 288.29 110.49) (xy 288.29 116.84)
		)
		(stroke
			(width 0)
			(type default)
		)
	)
	(wire
		(pts
			(xy 182.88 68.58) (xy 182.88 69.85)
		)
		(stroke
			(width 0)
			(type default)
		)
	)
	(wire
		(pts
			(xy 256.54 60.96) (xy 261.62 60.96)
		)
		(stroke
			(width 0)
			(type default)
		)
	)
	(wire
		(pts
			(xy 186.69 92.71) (xy 186.69 87.63)
		)
		(stroke
			(width 0)
			(type default)
		)
	)
	(wire
		(pts
			(xy 62.23 213.36) (xy 64.77 213.36)
		)
		(stroke
			(width 0)
			(type default)
		)
	)
	(wire
		(pts
			(xy 288.29 60.96) (xy 288.29 67.31)
		)
		(stroke
			(width 0)
			(type default)
		)
	)
	(wire
		(pts
			(xy 288.29 116.84) (xy 278.13 116.84)
		)
		(stroke
			(width 0)
			(type default)
		)
	)
	(wire
		(pts
			(xy 231.14 205.74) (xy 234.95 205.74)
		)
		(stroke
			(width 0)
			(type default)
		)
	)
	(wire
		(pts
			(xy 20.32 229.87) (xy 20.32 231.14)
		)
		(stroke
			(width 0)
			(type default)
		)
	)
	(wire
		(pts
			(xy 196.85 105.41) (xy 212.09 105.41)
		)
		(stroke
			(width 0)
			(type default)
		)
	)
	(wire
		(pts
			(xy 209.55 83.82) (xy 212.09 83.82)
		)
		(stroke
			(width 0)
			(type default)
		)
	)
	(wire
		(pts
			(xy 276.86 90.17) (xy 275.59 90.17)
		)
		(stroke
			(width 0)
			(type default)
		)
	)
	(wire
		(pts
			(xy 275.59 234.95) (xy 275.59 240.03)
		)
		(stroke
			(width 0)
			(type default)
		)
	)
	(wire
		(pts
			(xy 231.14 205.74) (xy 231.14 214.63)
		)
		(stroke
			(width 0)
			(type default)
		)
	)
	(wire
		(pts
			(xy 256.54 227.33) (xy 256.54 229.87)
		)
		(stroke
			(width 0)
			(type default)
		)
	)
	(bus
		(pts
			(xy 194.31 254) (xy 195.58 254)
		)
		(stroke
			(width 0)
			(type default)
		)
	)
	(wire
		(pts
			(xy 238.76 68.58) (xy 238.76 45.72)
		)
		(stroke
			(width 0)
			(type default)
		)
	)
	(wire
		(pts
			(xy 173.99 153.67) (xy 172.72 153.67)
		)
		(stroke
			(width 0)
			(type default)
		)
	)
	(wire
		(pts
			(xy 271.78 110.49) (xy 275.59 110.49)
		)
		(stroke
			(width 0)
			(type default)
		)
	)
	(wire
		(pts
			(xy 237.49 78.74) (xy 246.38 78.74)
		)
		(stroke
			(width 0)
			(type default)
		)
	)
	(wire
		(pts
			(xy 290.83 240.03) (xy 302.26 240.03)
		)
		(stroke
			(width 0)
			(type default)
		)
	)
	(polyline
		(pts
			(xy 381 82.55) (xy 381 95.25)
		)
		(stroke
			(width 0)
			(type default)
		)
	)
	(polyline
		(pts
			(xy 407.67 170.18) (xy 12.7 170.18)
		)
		(stroke
			(width 0)
			(type dash)
		)
	)
	(wire
		(pts
			(xy 88.9 236.22) (xy 88.9 237.49)
		)
		(stroke
			(width 0)
			(type default)
		)
	)
	(wire
		(pts
			(xy 93.98 62.23) (xy 115.57 62.23)
		)
		(stroke
			(width 0)
			(type default)
		)
	)
	(wire
		(pts
			(xy 217.17 207.01) (xy 217.17 208.28)
		)
		(stroke
			(width 0)
			(type default)
		)
	)
	(wire
		(pts
			(xy 85.09 251.46) (xy 85.09 252.73)
		)
		(stroke
			(width 0)
			(type default)
		)
	)
	(wire
		(pts
			(xy 200.66 68.58) (xy 200.66 69.85)
		)
		(stroke
			(width 0)
			(type default)
		)
	)
	(wire
		(pts
			(xy 265.43 234.95) (xy 275.59 234.95)
		)
		(stroke
			(width 0)
			(type default)
		)
	)
	(wire
		(pts
			(xy 365.76 120.65) (xy 365.76 121.92)
		)
		(stroke
			(width 0)
			(type default)
		)
	)
	(wire
		(pts
			(xy 88.9 203.2) (xy 88.9 205.74)
		)
		(stroke
			(width 0)
			(type default)
		)
	)
	(bus
		(pts
			(xy 43.18 41.91) (xy 43.18 52.07)
		)
		(stroke
			(width 0)
			(type default)
		)
	)
	(wire
		(pts
			(xy 290.83 228.6) (xy 302.26 228.6)
		)
		(stroke
			(width 0)
			(type default)
		)
	)
	(wire
		(pts
			(xy 275.59 240.03) (xy 290.83 240.03)
		)
		(stroke
			(width 0)
			(type default)
		)
	)
	(polyline
		(pts
			(xy 350.52 87.63) (xy 350.52 105.41)
		)
		(stroke
			(width 0)
			(type default)
		)
	)
	(wire
		(pts
			(xy 288.29 92.71) (xy 289.56 92.71)
		)
		(stroke
			(width 0)
			(type default)
		)
	)
	(wire
		(pts
			(xy 262.89 127) (xy 262.89 128.27)
		)
		(stroke
			(width 0)
			(type default)
		)
	)
	(wire
		(pts
			(xy 189.23 227.33) (xy 189.23 229.87)
		)
		(stroke
			(width 0)
			(type default)
		)
	)
	(wire
		(pts
			(xy 365.76 133.35) (xy 365.76 135.89)
		)
		(stroke
			(width 0)
			(type default)
		)
	)
	(wire
		(pts
			(xy 220.98 224.79) (xy 213.36 224.79)
		)
		(stroke
			(width 0)
			(type default)
		)
	)
	(bus
		(pts
			(xy 43.18 52.07) (xy 43.18 54.61)
		)
		(stroke
			(width 0)
			(type default)
		)
	)
	(wire
		(pts
			(xy 243.84 99.06) (xy 243.84 113.03)
		)
		(stroke
			(width 0)
			(type default)
		)
	)
	(wire
		(pts
			(xy 271.78 110.49) (xy 271.78 111.76)
		)
		(stroke
			(width 0)
			(type default)
		)
	)
	(wire
		(pts
			(xy 93.98 64.77) (xy 97.79 64.77)
		)
		(stroke
			(width 0)
			(type default)
		)
	)
	(wire
		(pts
			(xy 294.64 45.72) (xy 295.91 45.72)
		)
		(stroke
			(width 0)
			(type default)
		)
	)
	(wire
		(pts
			(xy 198.12 208.28) (xy 207.01 208.28)
		)
		(stroke
			(width 0)
			(type default)
		)
	)
	(wire
		(pts
			(xy 311.15 212.09) (xy 311.15 219.71)
		)
		(stroke
			(width 0)
			(type default)
		)
	)
	(wire
		(pts
			(xy 252.73 242.57) (xy 252.73 243.84)
		)
		(stroke
			(width 0)
			(type default)
		)
	)
	(wire
		(pts
			(xy 195.58 92.71) (xy 212.09 92.71)
		)
		(stroke
			(width 0)
			(type default)
		)
	)
	(wire
		(pts
			(xy 288.29 52.07) (xy 278.13 52.07)
		)
		(stroke
			(width 0)
			(type default)
		)
	)
	(wire
		(pts
			(xy 278.13 127) (xy 278.13 132.08)
		)
		(stroke
			(width 0)
			(type default)
		)
	)
	(wire
		(pts
			(xy 261.62 110.49) (xy 261.62 111.76)
		)
		(stroke
			(width 0)
			(type default)
		)
	)
	(wire
		(pts
			(xy 262.89 76.2) (xy 262.89 77.47)
		)
		(stroke
			(width 0)
			(type default)
		)
	)
	(wire
		(pts
			(xy 189.23 208.28) (xy 189.23 210.82)
		)
		(stroke
			(width 0)
			(type default)
		)
	)
	(polyline
		(pts
			(xy 355.6 92.71) (xy 355.6 105.41)
		)
		(stroke
			(width 0)
			(type default)
		)
	)
	(wire
		(pts
			(xy 55.88 64.77) (xy 66.04 64.77)
		)
		(stroke
			(width 0)
			(type default)
		)
	)
	(wire
		(pts
			(xy 33.02 59.69) (xy 33.02 60.96)
		)
		(stroke
			(width 0)
			(type default)
		)
	)
	(wire
		(pts
			(xy 200.66 74.93) (xy 200.66 76.2)
		)
		(stroke
			(width 0)
			(type default)
		)
	)
	(wire
		(pts
			(xy 93.98 52.07) (xy 115.57 52.07)
		)
		(stroke
			(width 0)
			(type default)
		)
	)
	(wire
		(pts
			(xy 265.43 227.33) (xy 265.43 229.87)
		)
		(stroke
			(width 0)
			(type default)
		)
	)
	(wire
		(pts
			(xy 20.32 217.17) (xy 20.32 223.52)
		)
		(stroke
			(width 0)
			(type default)
		)
	)
	(polyline
		(pts
			(xy 386.08 92.71) (xy 386.08 105.41)
		)
		(stroke
			(width 0)
			(type default)
		)
	)
	(wire
		(pts
			(xy 207.01 208.28) (xy 217.17 208.28)
		)
		(stroke
			(width 0)
			(type default)
		)
	)
	(wire
		(pts
			(xy 209.55 80.01) (xy 212.09 80.01)
		)
		(stroke
			(width 0)
			(type default)
		)
	)
	(polyline
		(pts
			(xy 321.31 105.41) (xy 391.16 105.41)
		)
		(stroke
			(width 0)
			(type default)
		)
	)
	(wire
		(pts
			(xy 209.55 83.82) (xy 209.55 87.63)
		)
		(stroke
			(width 0)
			(type default)
		)
	)
	(wire
		(pts
			(xy 165.1 68.58) (xy 165.1 69.85)
		)
		(stroke
			(width 0)
			(type default)
		)
	)
	(wire
		(pts
			(xy 262.89 133.35) (xy 262.89 134.62)
		)
		(stroke
			(width 0)
			(type default)
		)
	)
	(wire
		(pts
			(xy 217.17 219.71) (xy 220.98 219.71)
		)
		(stroke
			(width 0)
			(type default)
		)
	)
	(wire
		(pts
			(xy 243.84 113.03) (xy 257.81 113.03)
		)
		(stroke
			(width 0)
			(type default)
		)
	)
	(wire
		(pts
			(xy 294.64 76.2) (xy 299.72 76.2)
		)
		(stroke
			(width 0)
			(type default)
		)
	)
	(wire
		(pts
			(xy 261.62 92.71) (xy 261.62 93.98)
		)
		(stroke
			(width 0)
			(type default)
		)
	)
	(wire
		(pts
			(xy 241.3 234.95) (xy 260.35 234.95)
		)
		(stroke
			(width 0)
			(type default)
		)
	)
	(wire
		(pts
			(xy 294.64 92.71) (xy 295.91 92.71)
		)
		(stroke
			(width 0)
			(type default)
		)
	)
	(wire
		(pts
			(xy 173.99 68.58) (xy 173.99 69.85)
		)
		(stroke
			(width 0)
			(type default)
		)
	)
	(wire
		(pts
			(xy 276.86 43.18) (xy 276.86 45.72)
		)
		(stroke
			(width 0)
			(type default)
		)
	)
	(wire
		(pts
			(xy 354.33 134.62) (xy 354.33 135.89)
		)
		(stroke
			(width 0)
			(type default)
		)
	)
	(wire
		(pts
			(xy 229.87 247.65) (xy 229.87 248.92)
		)
		(stroke
			(width 0)
			(type default)
		)
	)
	(wire
		(pts
			(xy 261.62 45.72) (xy 261.62 46.99)
		)
		(stroke
			(width 0)
			(type default)
		)
	)
	(wire
		(pts
			(xy 218.44 233.68) (xy 220.98 233.68)
		)
		(stroke
			(width 0)
			(type default)
		)
	)
	(wire
		(pts
			(xy 243.84 219.71) (xy 247.65 219.71)
		)
		(stroke
			(width 0)
			(type default)
		)
	)
	(wire
		(pts
			(xy 237.49 76.2) (xy 243.84 76.2)
		)
		(stroke
			(width 0)
			(type default)
		)
	)
	(wire
		(pts
			(xy 299.72 110.49) (xy 299.72 109.22)
		)
		(stroke
			(width 0)
			(type default)
		)
	)
	(wire
		(pts
			(xy 189.23 234.95) (xy 189.23 237.49)
		)
		(stroke
			(width 0)
			(type default)
		)
	)
	(wire
		(pts
			(xy 62.23 242.57) (xy 62.23 243.84)
		)
		(stroke
			(width 0)
			(type default)
		)
	)
	(wire
		(pts
			(xy 241.3 242.57) (xy 252.73 242.57)
		)
		(stroke
			(width 0)
			(type default)
		)
	)
	(wire
		(pts
			(xy 262.89 76.2) (xy 276.86 76.2)
		)
		(stroke
			(width 0)
			(type default)
		)
	)
	(wire
		(pts
			(xy 63.5 67.31) (xy 63.5 72.39)
		)
		(stroke
			(width 0)
			(type default)
		)
	)
	(polyline
		(pts
			(xy 386.08 82.55) (xy 386.08 95.25)
		)
		(stroke
			(width 0)
			(type default)
		)
	)
	(wire
		(pts
			(xy 288.29 60.96) (xy 289.56 60.96)
		)
		(stroke
			(width 0)
			(type default)
		)
	)
	(wire
		(pts
			(xy 256.54 110.49) (xy 257.81 110.49)
		)
		(stroke
			(width 0)
			(type default)
		)
	)
	(wire
		(pts
			(xy 295.91 99.06) (xy 306.07 99.06)
		)
		(stroke
			(width 0)
			(type default)
		)
	)
	(wire
		(pts
			(xy 64.77 49.53) (xy 66.04 49.53)
		)
		(stroke
			(width 0)
			(type default)
		)
	)
	(wire
		(pts
			(xy 55.88 66.04) (xy 55.88 64.77)
		)
		(stroke
			(width 0)
			(type default)
		)
	)
	(wire
		(pts
			(xy 158.75 129.54) (xy 160.02 129.54)
		)
		(stroke
			(width 0)
			(type default)
		)
	)
	(wire
		(pts
			(xy 212.09 68.58) (xy 209.55 68.58)
		)
		(stroke
			(width 0)
			(type default)
		)
	)
	(wire
		(pts
			(xy 347.98 144.78) (xy 354.33 144.78)
		)
		(stroke
			(width 0)
			(type default)
		)
	)
	(wire
		(pts
			(xy 261.62 67.31) (xy 261.62 68.58)
		)
		(stroke
			(width 0)
			(type default)
		)
	)
	(wire
		(pts
			(xy 290.83 228.6) (xy 290.83 232.41)
		)
		(stroke
			(width 0)
			(type default)
		)
	)
	(wire
		(pts
			(xy 238.76 109.22) (xy 238.76 143.51)
		)
		(stroke
			(width 0)
			(type default)
		)
	)
	(wire
		(pts
			(xy 248.92 88.9) (xy 248.92 92.71)
		)
		(stroke
			(width 0)
			(type default)
		)
	)
	(polyline
		(pts
			(xy 365.76 82.55) (xy 365.76 95.25)
		)
		(stroke
			(width 0)
			(type default)
		)
	)
	(wire
		(pts
			(xy 86.36 205.74) (xy 86.36 210.82)
		)
		(stroke
			(width 0)
			(type default)
		)
	)
	(polyline
		(pts
			(xy 391.16 80.01) (xy 391.16 95.25)
		)
		(stroke
			(width 0)
			(type default)
		)
	)
	(wire
		(pts
			(xy 273.05 219.71) (xy 281.94 219.71)
		)
		(stroke
			(width 0)
			(type default)
		)
	)
	(wire
		(pts
			(xy 93.98 54.61) (xy 97.79 54.61)
		)
		(stroke
			(width 0)
			(type default)
		)
	)
	(wire
		(pts
			(xy 165.1 67.31) (xy 165.1 68.58)
		)
		(stroke
			(width 0)
			(type default)
		)
	)
	(wire
		(pts
			(xy 82.55 218.44) (xy 85.09 218.44)
		)
		(stroke
			(width 0)
			(type default)
		)
	)
	(wire
		(pts
			(xy 182.88 68.58) (xy 191.77 68.58)
		)
		(stroke
			(width 0)
			(type default)
		)
	)
	(polyline
		(pts
			(xy 321.31 100.33) (xy 391.16 100.33)
		)
		(stroke
			(width 0)
			(type default)
		)
	)
	(wire
		(pts
			(xy 231.14 248.92) (xy 231.14 250.19)
		)
		(stroke
			(width 0)
			(type default)
		)
	)
	(wire
		(pts
			(xy 88.9 205.74) (xy 91.44 205.74)
		)
		(stroke
			(width 0)
			(type default)
		)
	)
	(wire
		(pts
			(xy 209.55 80.01) (xy 209.55 83.82)
		)
		(stroke
			(width 0)
			(type default)
		)
	)
	(wire
		(pts
			(xy 281.94 227.33) (xy 281.94 229.87)
		)
		(stroke
			(width 0)
			(type default)
		)
	)
	(wire
		(pts
			(xy 60.96 62.23) (xy 66.04 62.23)
		)
		(stroke
			(width 0)
			(type default)
		)
	)
	(wire
		(pts
			(xy 281.94 219.71) (xy 281.94 222.25)
		)
		(stroke
			(width 0)
			(type default)
		)
	)
	(wire
		(pts
			(xy 299.72 74.93) (xy 299.72 76.2)
		)
		(stroke
			(width 0)
			(type default)
		)
	)
	(wire
		(pts
			(xy 63.5 127) (xy 63.5 128.27)
		)
		(stroke
			(width 0)
			(type default)
		)
	)
	(wire
		(pts
			(xy 295.91 92.71) (xy 299.72 92.71)
		)
		(stroke
			(width 0)
			(type default)
		)
	)
	(wire
		(pts
			(xy 261.62 52.07) (xy 261.62 53.34)
		)
		(stroke
			(width 0)
			(type default)
		)
	)
	(wire
		(pts
			(xy 261.62 99.06) (xy 261.62 100.33)
		)
		(stroke
			(width 0)
			(type default)
		)
	)
	(polyline
		(pts
			(xy 123.19 92.71) (xy 12.7 92.71)
		)
		(stroke
			(width 0)
			(type dash)
		)
	)
	(polyline
		(pts
			(xy 321.31 95.25) (xy 321.31 105.41)
		)
		(stroke
			(width 0)
			(type default)
		)
	)
	(polyline
		(pts
			(xy 375.92 92.71) (xy 375.92 105.41)
		)
		(stroke
			(width 0)
			(type default)
		)
	)
	(wire
		(pts
			(xy 173.99 151.13) (xy 172.72 151.13)
		)
		(stroke
			(width 0)
			(type default)
		)
	)
	(wire
		(pts
			(xy 256.54 219.71) (xy 256.54 222.25)
		)
		(stroke
			(width 0)
			(type default)
		)
	)
	(wire
		(pts
			(xy 252.73 219.71) (xy 256.54 219.71)
		)
		(stroke
			(width 0)
			(type default)
		)
	)
	(wire
		(pts
			(xy 173.99 68.58) (xy 182.88 68.58)
		)
		(stroke
			(width 0)
			(type default)
		)
	)
	(wire
		(pts
			(xy 237.49 104.14) (xy 241.3 104.14)
		)
		(stroke
			(width 0)
			(type default)
		)
	)
	(wire
		(pts
			(xy 288.29 45.72) (xy 289.56 45.72)
		)
		(stroke
			(width 0)
			(type default)
		)
	)
	(wire
		(pts
			(xy 243.84 60.96) (xy 248.92 60.96)
		)
		(stroke
			(width 0)
			(type default)
		)
	)
	(wire
		(pts
			(xy 257.81 92.71) (xy 257.81 95.25)
		)
		(stroke
			(width 0)
			(type default)
		)
	)
	(wire
		(pts
			(xy 295.91 60.96) (xy 295.91 67.31)
		)
		(stroke
			(width 0)
			(type default)
		)
	)
	(wire
		(pts
			(xy 217.17 242.57) (xy 220.98 242.57)
		)
		(stroke
			(width 0)
			(type default)
		)
	)
	(wire
		(pts
			(xy 302.26 228.6) (xy 302.26 232.41)
		)
		(stroke
			(width 0)
			(type default)
		)
	)
	(wire
		(pts
			(xy 82.55 251.46) (xy 85.09 251.46)
		)
		(stroke
			(width 0)
			(type default)
		)
	)
	(polyline
		(pts
			(xy 330.2 83.82) (xy 330.2 95.25)
		)
		(stroke
			(width 0)
			(type default)
		)
	)
	(wire
		(pts
			(xy 270.51 52.07) (xy 270.51 53.34)
		)
		(stroke
			(width 0)
			(type default)
		)
	)
	(wire
		(pts
			(xy 278.13 127) (xy 279.4 127)
		)
		(stroke
			(width 0)
			(type default)
		)
	)
	(wire
		(pts
			(xy 198.12 208.28) (xy 198.12 210.82)
		)
		(stroke
			(width 0)
			(type default)
		)
	)
	(wire
		(pts
			(xy 237.49 91.44) (xy 246.38 91.44)
		)
		(stroke
			(width 0)
			(type default)
		)
	)
	(wire
		(pts
			(xy 354.33 144.78) (xy 359.41 144.78)
		)
		(stroke
			(width 0)
			(type default)
		)
	)
	(wire
		(pts
			(xy 281.94 214.63) (xy 283.21 214.63)
		)
		(stroke
			(width 0)
			(type default)
		)
	)
	(wire
		(pts
			(xy 275.59 92.71) (xy 288.29 92.71)
		)
		(stroke
			(width 0)
			(type default)
		)
	)
	(wire
		(pts
			(xy 265.43 219.71) (xy 265.43 222.25)
		)
		(stroke
			(width 0)
			(type default)
		)
	)
	(wire
		(pts
			(xy 276.86 45.72) (xy 288.29 45.72)
		)
		(stroke
			(width 0)
			(type default)
		)
	)
	(polyline
		(pts
			(xy 391.16 85.09) (xy 391.16 105.41)
		)
		(stroke
			(width 0)
			(type default)
		)
	)
	(wire
		(pts
			(xy 248.92 76.2) (xy 248.92 83.82)
		)
		(stroke
			(width 0)
			(type default)
		)
	)
	(wire
		(pts
			(xy 158.75 134.62) (xy 160.02 134.62)
		)
		(stroke
			(width 0)
			(type default)
		)
	)
	(wire
		(pts
			(xy 365.76 147.32) (xy 365.76 152.4)
		)
		(stroke
			(width 0)
			(type default)
		)
	)
	(bus
		(pts
			(xy 196.85 252.73) (xy 196.85 242.57)
		)
		(stroke
			(width 0)
			(type default)
		)
	)
	(polyline
		(pts
			(xy 321.31 90.17) (xy 391.16 90.17)
		)
		(stroke
			(width 0)
			(type default)
		)
	)
	(wire
		(pts
			(xy 241.3 71.12) (xy 237.49 71.12)
		)
		(stroke
			(width 0)
			(type default)
		)
	)
	(wire
		(pts
			(xy 45.72 54.61) (xy 66.04 54.61)
		)
		(stroke
			(width 0)
			(type default)
		)
	)
	(wire
		(pts
			(xy 256.54 45.72) (xy 261.62 45.72)
		)
		(stroke
			(width 0)
			(type default)
		)
	)
	(wire
		(pts
			(xy 290.83 247.65) (xy 290.83 250.19)
		)
		(stroke
			(width 0)
			(type default)
		)
	)
	(wire
		(pts
			(xy 246.38 78.74) (xy 246.38 63.5)
		)
		(stroke
			(width 0)
			(type default)
		)
	)
	(wire
		(pts
			(xy 60.96 135.89) (xy 63.5 135.89)
		)
		(stroke
			(width 0)
			(type default)
		)
	)
	(wire
		(pts
			(xy 182.88 74.93) (xy 182.88 76.2)
		)
		(stroke
			(width 0)
			(type default)
		)
	)
	(polyline
		(pts
			(xy 330.2 82.55) (xy 330.2 83.82)
		)
		(stroke
			(width 0)
			(type default)
		)
	)
	(wire
		(pts
			(xy 208.28 101.6) (xy 212.09 101.6)
		)
		(stroke
			(width 0)
			(type default)
		)
	)
	(wire
		(pts
			(xy 238.76 68.58) (xy 237.49 68.58)
		)
		(stroke
			(width 0)
			(type default)
		)
	)
	(polyline
		(pts
			(xy 350.52 82.55) (xy 350.52 95.25)
		)
		(stroke
			(width 0)
			(type default)
		)
	)
	(wire
		(pts
			(xy 172.72 153.67) (xy 172.72 151.13)
		)
		(stroke
			(width 0)
			(type default)
		)
	)
	(wire
		(pts
			(xy 189.23 208.28) (xy 198.12 208.28)
		)
		(stroke
			(width 0)
			(type default)
		)
	)
	(wire
		(pts
			(xy 284.48 127) (xy 292.1 127)
		)
		(stroke
			(width 0)
			(type default)
		)
	)
	(bus
		(pts
			(xy 191.77 120.65) (xy 193.04 120.65)
		)
		(stroke
			(width 0)
			(type default)
		)
	)
	(wire
		(pts
			(xy 172.72 148.59) (xy 172.72 151.13)
		)
		(stroke
			(width 0)
			(type default)
		)
	)
	(wire
		(pts
			(xy 311.15 219.71) (xy 312.42 219.71)
		)
		(stroke
			(width 0)
			(type default)
		)
	)
	(wire
		(pts
			(xy 157.48 143.51) (xy 156.21 143.51)
		)
		(stroke
			(width 0)
			(type default)
		)
	)
	(wire
		(pts
			(xy 189.23 218.44) (xy 189.23 219.71)
		)
		(stroke
			(width 0)
			(type default)
		)
	)
	(wire
		(pts
			(xy 62.23 243.84) (xy 64.77 243.84)
		)
		(stroke
			(width 0)
			(type default)
		)
	)
	(wire
		(pts
			(xy 93.98 59.69) (xy 97.79 59.69)
		)
		(stroke
			(width 0)
			(type default)
		)
	)
	(wire
		(pts
			(xy 63.5 143.51) (xy 63.5 144.78)
		)
		(stroke
			(width 0)
			(type default)
		)
	)
	(wire
		(pts
			(xy 20.32 229.87) (xy 33.02 229.87)
		)
		(stroke
			(width 0)
			(type default)
		)
	)
	(wire
		(pts
			(xy 281.94 219.71) (xy 290.83 219.71)
		)
		(stroke
			(width 0)
			(type default)
		)
	)
	(wire
		(pts
			(xy 189.23 207.01) (xy 189.23 208.28)
		)
		(stroke
			(width 0)
			(type default)
		)
	)
	(wire
		(pts
			(xy 198.12 215.9) (xy 198.12 218.44)
		)
		(stroke
			(width 0)
			(type default)
		)
	)
	(wire
		(pts
			(xy 241.3 227.33) (xy 252.73 227.33)
		)
		(stroke
			(width 0)
			(type default)
		)
	)
	(wire
		(pts
			(xy 279.4 148.59) (xy 278.13 148.59)
		)
		(stroke
			(width 0)
			(type default)
		)
	)
	(polyline
		(pts
			(xy 340.36 82.55) (xy 340.36 95.25)
		)
		(stroke
			(width 0)
			(type default)
		)
	)
	(wire
		(pts
			(xy 62.23 210.82) (xy 64.77 210.82)
		)
		(stroke
			(width 0)
			(type default)
		)
	)
	(wire
		(pts
			(xy 93.98 57.15) (xy 115.57 57.15)
		)
		(stroke
			(width 0)
			(type default)
		)
	)
	(wire
		(pts
			(xy 299.72 45.72) (xy 299.72 44.45)
		)
		(stroke
			(width 0)
			(type default)
		)
	)
	(polyline
		(pts
			(xy 123.19 12.7) (xy 123.19 284.48)
		)
		(stroke
			(width 0)
			(type dash)
		)
	)
	(wire
		(pts
			(xy 276.86 107.95) (xy 275.59 107.95)
		)
		(stroke
			(width 0)
			(type default)
		)
	)
	(bus
		(pts
			(xy 194.31 110.49) (xy 194.31 119.38)
		)
		(stroke
			(width 0)
			(type default)
		)
	)
	(wire
		(pts
			(xy 295.91 110.49) (xy 299.72 110.49)
		)
		(stroke
			(width 0)
			(type default)
		)
	)
	(wire
		(pts
			(xy 295.91 45.72) (xy 295.91 52.07)
		)
		(stroke
			(width 0)
			(type default)
		)
	)
	(polyline
		(pts
			(xy 321.31 92.71) (xy 391.16 92.71)
		)
		(stroke
			(width 0)
			(type default)
		)
	)
	(wire
		(pts
			(xy 102.87 54.61) (xy 115.57 54.61)
		)
		(stroke
			(width 0)
			(type default)
		)
	)
	(wire
		(pts
			(xy 295.91 67.31) (xy 306.07 67.31)
		)
		(stroke
			(width 0)
			(type default)
		)
	)
	(wire
		(pts
			(xy 91.44 213.36) (xy 99.06 213.36)
		)
		(stroke
			(width 0)
			(type default)
		)
	)
	(wire
		(pts
			(xy 241.3 104.14) (xy 241.3 127)
		)
		(stroke
			(width 0)
			(type default)
		)
	)
	(wire
		(pts
			(xy 74.93 135.89) (xy 85.09 135.89)
		)
		(stroke
			(width 0)
			(type default)
		)
	)
	(wire
		(pts
			(xy 276.86 60.96) (xy 288.29 60.96)
		)
		(stroke
			(width 0)
			(type default)
		)
	)
	(wire
		(pts
			(xy 248.92 83.82) (xy 237.49 83.82)
		)
		(stroke
			(width 0)
			(type default)
		)
	)
	(wire
		(pts
			(xy 217.17 243.84) (xy 217.17 242.57)
		)
		(stroke
			(width 0)
			(type default)
		)
	)
	(wire
		(pts
			(xy 231.14 248.92) (xy 232.41 248.92)
		)
		(stroke
			(width 0)
			(type default)
		)
	)
	(wire
		(pts
			(xy 195.58 100.33) (xy 195.58 99.06)
		)
		(stroke
			(width 0)
			(type default)
		)
	)
	(wire
		(pts
			(xy 271.78 60.96) (xy 276.86 60.96)
		)
		(stroke
			(width 0)
			(type default)
		)
	)
	(wire
		(pts
			(xy 189.23 227.33) (xy 220.98 227.33)
		)
		(stroke
			(width 0)
			(type default)
		)
	)
	(wire
		(pts
			(xy 156.21 146.05) (xy 157.48 146.05)
		)
		(stroke
			(width 0)
			(type default)
		)
	)
	(wire
		(pts
			(xy 295.91 52.07) (xy 306.07 52.07)
		)
		(stroke
			(width 0)
			(type default)
		)
	)
	(polyline
		(pts
			(xy 340.36 87.63) (xy 340.36 105.41)
		)
		(stroke
			(width 0)
			(type default)
		)
	)
	(wire
		(pts
			(xy 165.1 68.58) (xy 173.99 68.58)
		)
		(stroke
			(width 0)
			(type default)
		)
	)
	(wire
		(pts
			(xy 160.02 132.08) (xy 160.02 129.54)
		)
		(stroke
			(width 0)
			(type default)
		)
	)
	(wire
		(pts
			(xy 252.73 248.92) (xy 252.73 250.19)
		)
		(stroke
			(width 0)
			(type default)
		)
	)
	(wire
		(pts
			(xy 284.48 143.51) (xy 292.1 143.51)
		)
		(stroke
			(width 0)
			(type default)
		)
	)
	(wire
		(pts
			(xy 246.38 96.52) (xy 246.38 110.49)
		)
		(stroke
			(width 0)
			(type default)
		)
	)
	(wire
		(pts
			(xy 62.23 210.82) (xy 62.23 213.36)
		)
		(stroke
			(width 0)
			(type default)
		)
	)
	(wire
		(pts
			(xy 207.01 208.28) (xy 207.01 210.82)
		)
		(stroke
			(width 0)
			(type default)
		)
	)
	(polyline
		(pts
			(xy 370.84 82.55) (xy 370.84 95.25)
		)
		(stroke
			(width 0)
			(type default)
		)
	)
	(wire
		(pts
			(xy 237.49 109.22) (xy 238.76 109.22)
		)
		(stroke
			(width 0)
			(type default)
		)
	)
	(wire
		(pts
			(xy 290.83 240.03) (xy 290.83 242.57)
		)
		(stroke
			(width 0)
			(type default)
		)
	)
	(bus
		(pts
			(xy 195.58 254) (xy 196.85 252.73)
		)
		(stroke
			(width 0)
			(type default)
		)
	)
	(wire
		(pts
			(xy 237.49 99.06) (xy 243.84 99.06)
		)
		(stroke
			(width 0)
			(type default)
		)
	)
	(wire
		(pts
			(xy 158.75 132.08) (xy 160.02 132.08)
		)
		(stroke
			(width 0)
			(type default)
		)
	)
	(wire
		(pts
			(xy 261.62 92.71) (xy 271.78 92.71)
		)
		(stroke
			(width 0)
			(type default)
		)
	)
	(wire
		(pts
			(xy 278.13 143.51) (xy 279.4 143.51)
		)
		(stroke
			(width 0)
			(type default)
		)
	)
	(wire
		(pts
			(xy 278.13 43.18) (xy 276.86 43.18)
		)
		(stroke
			(width 0)
			(type default)
		)
	)
	(wire
		(pts
			(xy 173.99 74.93) (xy 173.99 76.2)
		)
		(stroke
			(width 0)
			(type default)
		)
	)
	(wire
		(pts
			(xy 261.62 110.49) (xy 271.78 110.49)
		)
		(stroke
			(width 0)
			(type default)
		)
	)
	(bus
		(pts
			(xy 40.64 40.64) (xy 41.91 40.64)
		)
		(stroke
			(width 0)
			(type default)
		)
	)
	(wire
		(pts
			(xy 156.21 143.51) (xy 156.21 146.05)
		)
		(stroke
			(width 0)
			(type default)
		)
	)
	(wire
		(pts
			(xy 209.55 76.2) (xy 209.55 80.01)
		)
		(stroke
			(width 0)
			(type default)
		)
	)
	(wire
		(pts
			(xy 295.91 45.72) (xy 299.72 45.72)
		)
		(stroke
			(width 0)
			(type default)
		)
	)
	(wire
		(pts
			(xy 275.59 107.95) (xy 275.59 110.49)
		)
		(stroke
			(width 0)
			(type default)
		)
	)
	(wire
		(pts
			(xy 275.59 90.17) (xy 275.59 92.71)
		)
		(stroke
			(width 0)
			(type default)
		)
	)
	(polyline
		(pts
			(xy 365.76 92.71) (xy 365.76 105.41)
		)
		(stroke
			(width 0)
			(type default)
		)
	)
	(wire
		(pts
			(xy 64.77 46.99) (xy 64.77 49.53)
		)
		(stroke
			(width 0)
			(type default)
		)
	)
	(wire
		(pts
			(xy 354.33 140.97) (xy 354.33 144.78)
		)
		(stroke
			(width 0)
			(type default)
		)
	)
	(wire
		(pts
			(xy 88.9 242.57) (xy 88.9 243.84)
		)
		(stroke
			(width 0)
			(type default)
		)
	)
	(wire
		(pts
			(xy 209.55 68.58) (xy 209.55 72.39)
		)
		(stroke
			(width 0)
			(type default)
		)
	)
	(wire
		(pts
			(xy 275.59 110.49) (xy 288.29 110.49)
		)
		(stroke
			(width 0)
			(type default)
		)
	)
	(wire
		(pts
			(xy 256.54 45.72) (xy 256.54 48.26)
		)
		(stroke
			(width 0)
			(type default)
		)
	)
	(wire
		(pts
			(xy 165.1 74.93) (xy 165.1 76.2)
		)
		(stroke
			(width 0)
			(type default)
		)
	)
	(wire
		(pts
			(xy 191.77 68.58) (xy 200.66 68.58)
		)
		(stroke
			(width 0)
			(type default)
		)
	)
	(wire
		(pts
			(xy 254 60.96) (xy 256.54 60.96)
		)
		(stroke
			(width 0)
			(type default)
		)
	)
	(wire
		(pts
			(xy 186.69 92.71) (xy 187.96 92.71)
		)
		(stroke
			(width 0)
			(type default)
		)
	)
	(wire
		(pts
			(xy 273.05 227.33) (xy 273.05 229.87)
		)
		(stroke
			(width 0)
			(type default)
		)
	)
	(polyline
		(pts
			(xy 321.31 97.79) (xy 391.16 97.79)
		)
		(stroke
			(width 0)
			(type default)
		)
	)
	(wire
		(pts
			(xy 271.78 67.31) (xy 271.78 68.58)
		)
		(stroke
			(width 0)
			(type default)
		)
	)
	(polyline
		(pts
			(xy 391.16 80.01) (xy 321.31 80.01)
		)
		(stroke
			(width 0)
			(type default)
		)
	)
	(polyline
		(pts
			(xy 321.31 87.63) (xy 391.16 87.63)
		)
		(stroke
			(width 0)
			(type default)
		)
	)
	(wire
		(pts
			(xy 288.29 110.49) (xy 289.56 110.49)
		)
		(stroke
			(width 0)
			(type default)
		)
	)
	(wire
		(pts
			(xy 298.45 219.71) (xy 311.15 219.71)
		)
		(stroke
			(width 0)
			(type default)
		)
	)
	(polyline
		(pts
			(xy 335.28 82.55) (xy 335.28 95.25)
		)
		(stroke
			(width 0)
			(type default)
		)
	)
	(wire
		(pts
			(xy 278.13 73.66) (xy 276.86 73.66)
		)
		(stroke
			(width 0)
			(type default)
		)
	)
	(wire
		(pts
			(xy 238.76 143.51) (xy 262.89 143.51)
		)
		(stroke
			(width 0)
			(type default)
		)
	)
	(wire
		(pts
			(xy 299.72 59.69) (xy 299.72 60.96)
		)
		(stroke
			(width 0)
			(type default)
		)
	)
	(polyline
		(pts
			(xy 391.16 82.55) (xy 330.2 82.55)
		)
		(stroke
			(width 0)
			(type default)
		)
	)
	(polyline
		(pts
			(xy 321.31 102.87) (xy 391.16 102.87)
		)
		(stroke
			(width 0)
			(type default)
		)
	)
	(wire
		(pts
			(xy 53.34 218.44) (xy 64.77 218.44)
		)
		(stroke
			(width 0)
			(type default)
		)
	)
	(wire
		(pts
			(xy 365.76 127) (xy 365.76 128.27)
		)
		(stroke
			(width 0)
			(type default)
		)
	)
	(wire
		(pts
			(xy 271.78 116.84) (xy 271.78 118.11)
		)
		(stroke
			(width 0)
			(type default)
		)
	)
	(wire
		(pts
			(xy 241.3 48.26) (xy 256.54 48.26)
		)
		(stroke
			(width 0)
			(type default)
		)
	)
	(label "SENSE1_N"
		(at 115.57 52.07 180)
		(effects
			(font
				(size 1.27 1.27)
			)
			(justify right bottom)
		)
	)
	(label "1V05_REG"
		(at 256.54 219.71 0)
		(effects
			(font
				(size 1.27 1.27)
			)
			(justify left bottom)
		)
	)
	(label "SUPPLY.SCL"
		(at 212.09 105.41 180)
		(effects
			(font
				(size 1.27 1.27)
			)
			(justify right bottom)
		)
	)
	(label "SUPPLY.SCL"
		(at 176.53 129.54 180)
		(effects
			(font
				(size 1.27 1.27)
			)
			(justify right bottom)
		)
	)
	(label "PG"
		(at 208.28 101.6 0)
		(effects
			(font
				(size 1.27 1.27)
			)
			(justify left bottom)
		)
	)
	(label "SUPPLY.SDA"
		(at 213.995 237.49 180)
		(effects
			(font
				(size 1.27 1.27)
			)
			(justify right bottom)
		)
	)
	(label "PR"
		(at 57.15 215.9 0)
		(effects
			(font
				(size 1.27 1.27)
			)
			(justify left bottom)
		)
	)
	(label "SENSE3_N"
		(at 306.07 67.31 180)
		(effects
			(font
				(size 1.27 1.27)
			)
			(justify right bottom)
		)
	)
	(label "PG"
		(at 218.44 233.68 0)
		(effects
			(font
				(size 1.27 1.27)
			)
			(justify left bottom)
		)
	)
	(label "SENSE4_P"
		(at 278.13 116.84 0)
		(effects
			(font
				(size 1.27 1.27)
			)
			(justify left bottom)
		)
	)
	(label "SENSE4_P"
		(at 115.57 64.77 180)
		(effects
			(font
				(size 1.27 1.27)
			)
			(justify right bottom)
		)
	)
	(label "SENSE1_N"
		(at 306.07 52.07 180)
		(effects
			(font
				(size 1.27 1.27)
			)
			(justify right bottom)
		)
	)
	(label "SENSE2_P"
		(at 278.13 99.06 0)
		(effects
			(font
				(size 1.27 1.27)
			)
			(justify left bottom)
		)
	)
	(label "SENSE1_P"
		(at 115.57 49.53 180)
		(effects
			(font
				(size 1.27 1.27)
			)
			(justify right bottom)
		)
	)
	(label "1V05_VCC"
		(at 189.23 227.33 0)
		(effects
			(font
				(size 1.27 1.27)
			)
			(justify left bottom)
		)
	)
	(label "1V05_FB"
		(at 244.475 234.95 0)
		(effects
			(font
				(size 1.27 1.27)
			)
			(justify left bottom)
		)
	)
	(label "PG"
		(at 347.98 144.78 0)
		(effects
			(font
				(size 1.27 1.27)
			)
			(justify left bottom)
		)
	)
	(label "PWRON"
		(at 213.36 224.79 0)
		(effects
			(font
				(size 1.27 1.27)
			)
			(justify left bottom)
		)
	)
	(label "SENSE3_P"
		(at 115.57 59.69 180)
		(effects
			(font
				(size 1.27 1.27)
			)
			(justify right bottom)
		)
	)
	(label "SENSE3_P"
		(at 278.13 67.31 0)
		(effects
			(font
				(size 1.27 1.27)
			)
			(justify left bottom)
		)
	)
	(label "SENSE4_N"
		(at 306.07 116.84 180)
		(effects
			(font
				(size 1.27 1.27)
			)
			(justify right bottom)
		)
	)
	(label "1V05_REG"
		(at 252.73 227.33 180)
		(effects
			(font
				(size 1.27 1.27)
			)
			(justify right bottom)
		)
	)
	(label "SENSE3_N"
		(at 115.57 62.23 180)
		(effects
			(font
				(size 1.27 1.27)
			)
			(justify right bottom)
		)
	)
	(label "PWRON"
		(at 85.09 135.89 180)
		(effects
			(font
				(size 1.27 1.27)
			)
			(justify right bottom)
		)
	)
	(label "PWRON"
		(at 204.47 96.52 0)
		(effects
			(font
				(size 1.27 1.27)
			)
			(justify left bottom)
		)
	)
	(label "SENSE4_N"
		(at 115.57 67.31 180)
		(effects
			(font
				(size 1.27 1.27)
			)
			(justify right bottom)
		)
	)
	(label "SENSE2_N"
		(at 115.57 57.15 180)
		(effects
			(font
				(size 1.27 1.27)
			)
			(justify right bottom)
		)
	)
	(label "SENSE1_P"
		(at 278.13 52.07 0)
		(effects
			(font
				(size 1.27 1.27)
			)
			(justify left bottom)
		)
	)
	(label "SUPPLY.SCL"
		(at 213.995 240.03 180)
		(effects
			(font
				(size 1.27 1.27)
			)
			(justify right bottom)
		)
	)
	(label "SENSE2_P"
		(at 115.57 54.61 180)
		(effects
			(font
				(size 1.27 1.27)
			)
			(justify right bottom)
		)
	)
	(label "SUPPLY.SDA"
		(at 176.53 134.62 180)
		(effects
			(font
				(size 1.27 1.27)
			)
			(justify right bottom)
		)
	)
	(label "1V05_SW"
		(at 243.84 207.01 270)
		(effects
			(font
				(size 1.27 1.27)
			)
			(justify right bottom)
		)
	)
	(label "SUPPLY.SDA"
		(at 60.325 57.15 180)
		(effects
			(font
				(size 1.27 1.27)
			)
			(justify right bottom)
		)
	)
	(label "SUPPLY.SCL"
		(at 60.325 54.61 180)
		(effects
			(font
				(size 1.27 1.27)
			)
			(justify right bottom)
		)
	)
	(label "SUPPLY.SDA"
		(at 212.09 107.95 180)
		(effects
			(font
				(size 1.27 1.27)
			)
			(justify right bottom)
		)
	)
	(label "1V05_SS"
		(at 244.475 242.57 0)
		(effects
			(font
				(size 1.27 1.27)
			)
			(justify left bottom)
		)
	)
	(label "PR"
		(at 33.02 229.87 180)
		(effects
			(font
				(size 1.27 1.27)
			)
			(justify right bottom)
		)
	)
	(label "1V05_BS"
		(at 231.14 207.01 270)
		(effects
			(font
				(size 1.27 1.27)
			)
			(justify right bottom)
		)
	)
	(label "PR"
		(at 57.15 248.92 0)
		(effects
			(font
				(size 1.27 1.27)
			)
			(justify left bottom)
		)
	)
	(label "SENSE2_N"
		(at 306.07 99.06 180)
		(effects
			(font
				(size 1.27 1.27)
			)
			(justify right bottom)
		)
	)
	(global_label "1V8_CL"
		(shape input)
		(at 292.1 143.51 0)
		(fields_autoplaced yes)
		(effects
			(font
				(size 1.27 1.27)
			)
			(justify left)
		)
		(property "Intersheetrefs" "${INTERSHEET_REFS}"
			(at 301.8585 143.51 0)
			(effects
				(font
					(size 1.27 1.27)
				)
				(justify left)
			)
		)
	)
	(global_label "GLOBAL_EN"
		(shape input)
		(at 60.96 135.89 180)
		(fields_autoplaced yes)
		(effects
			(font
				(size 1.27 1.27)
			)
			(justify right)
		)
		(property "Intersheetrefs" "${INTERSHEET_REFS}"
			(at 47.5124 135.89 0)
			(effects
				(font
					(size 1.27 1.27)
				)
				(justify right)
			)
		)
	)
	(global_label "VREF_FLAG"
		(shape output)
		(at 99.06 213.36 0)
		(fields_autoplaced yes)
		(effects
			(font
				(size 1.27 1.27)
			)
			(justify left)
		)
		(property "Intersheetrefs" "${INTERSHEET_REFS}"
			(at 111.5121 213.2806 0)
			(effects
				(font
					(size 1.27 1.27)
				)
				(justify left)
			)
		)
	)
	(global_label "~{PG}"
		(shape input)
		(at 370.84 135.89 0)
		(fields_autoplaced yes)
		(effects
			(font
				(size 1.27 1.27)
			)
			(justify left)
		)
		(property "Intersheetrefs" "${INTERSHEET_REFS}"
			(at 376.3652 135.89 0)
			(effects
				(font
					(size 1.27 1.27)
				)
				(justify left)
			)
		)
	)
	(global_label "PAC1934_SLOW"
		(shape input)
		(at 60.96 59.69 180)
		(fields_autoplaced yes)
		(effects
			(font
				(size 1.27 1.27)
			)
			(justify right)
		)
		(property "Intersheetrefs" "${INTERSHEET_REFS}"
			(at 44.0931 59.6106 0)
			(effects
				(font
					(size 1.27 1.27)
				)
				(justify right)
			)
		)
	)
	(global_label "GPIO_VREF"
		(shape input)
		(at 20.32 217.17 90)
		(fields_autoplaced yes)
		(effects
			(font
				(size 1.27 1.27)
			)
			(justify left)
		)
		(property "Intersheetrefs" "${INTERSHEET_REFS}"
			(at 20.2406 204.7179 90)
			(effects
				(font
					(size 1.27 1.27)
				)
				(justify left)
			)
		)
	)
	(global_label "2V5_CL"
		(shape input)
		(at 292.1 127 0)
		(fields_autoplaced yes)
		(effects
			(font
				(size 1.27 1.27)
			)
			(justify left)
		)
		(property "Intersheetrefs" "${INTERSHEET_REFS}"
			(at 301.8585 127 0)
			(effects
				(font
					(size 1.27 1.27)
				)
				(justify left)
			)
		)
	)
	(hierarchical_label "SUPPLY{I^{2}C}"
		(shape input)
		(at 40.64 40.64 180)
		(effects
			(font
				(size 1.27 1.27)
			)
			(justify right)
		)
	)
	(hierarchical_label "SUPPLY{I^{2}C}"
		(shape input)
		(at 191.77 120.65 180)
		(effects
			(font
				(size 1.27 1.27)
			)
			(justify right)
		)
	)
	(hierarchical_label "SUPPLY{I^{2}C}"
		(shape input)
		(at 194.31 254 180)
		(effects
			(font
				(size 1.27 1.27)
			)
			(justify right)
		)
	)
	(symbol
		(lib_id "antmicroTestPoints:TP_0.75mm_SMD")
		(at 312.42 219.71 0)
		(unit 1)
		(exclude_from_sim no)
		(in_bom no)
		(on_board yes)
		(dnp no)
		(property "Reference" "TP35"
			(at 319.405 219.71 0)
			(effects
				(font
					(size 1.27 1.27)
					(thickness 0.15)
				)
			)
		)
		(property "Value" "TP_0.75mm_SMD"
			(at 323.215 223.52 0)
			(effects
				(font
					(size 1.27 1.27)
					(thickness 0.15)
				)
				(justify left bottom)
				(hide yes)
			)
		)
		(property "Footprint" "antmicro-footprints:TP_SMD_0.75mm"
			(at 323.215 226.06 0)
			(effects
				(font
					(size 1.27 1.27)
					(thickness 0.15)
				)
				(justify left bottom)
				(hide yes)
			)
		)
		(property "Datasheet" ""
			(at 330.2 232.41 0)
			(effects
				(font
					(size 1.27 1.27)
					(thickness 0.15)
				)
				(justify left bottom)
				(hide yes)
			)
		)
		(property "Description" "SMT test point"
			(at 312.42 219.71 0)
			(effects
				(font
					(size 1.27 1.27)
				)
				(hide yes)
			)
		)
		(property "MPN" ""
			(at 323.215 231.14 0)
			(effects
				(font
					(size 1.27 1.27)
					(thickness 0.15)
				)
				(justify left bottom)
				(hide yes)
			)
		)
		(property "Manufacturer" ""
			(at 323.215 226.06 0)
			(effects
				(font
					(size 1.27 1.27)
					(thickness 0.15)
				)
				(justify left bottom)
				(hide yes)
			)
		)
		(property "Author" "Antmicro"
			(at 323.215 228.6 0)
			(effects
				(font
					(size 1.27 1.27)
					(thickness 0.15)
				)
				(justify left bottom)
				(hide yes)
			)
		)
		(property "License" "Apache-2.0"
			(at 323.215 231.14 0)
			(effects
				(font
					(size 1.27 1.27)
					(thickness 0.15)
				)
				(justify left bottom)
				(hide yes)
			)
		)
		(property "Public" "False"
			(at 322.58 233.68 0)
			(effects
				(font
					(size 1.27 1.27)
				)
				(justify left bottom)
				(hide yes)
			)
		)
		(pin "1"
		)
		(instances
			(project "polarfire-som"
				(path ""
					(reference "TP35")
					(unit 1)
				)
			)
		)
	)
	(symbol
		(lib_id "antmicropower:+5V")
		(at 189.23 207.01 0)
		(unit 1)
		(exclude_from_sim no)
		(in_bom yes)
		(on_board yes)
		(dnp no)
		(fields_autoplaced yes)
		(property "Reference" "#PWR088"
			(at 204.47 209.55 0)
			(effects
				(font
					(size 1.27 1.27)
					(thickness 0.15)
				)
				(justify left bottom)
				(hide yes)
			)
		)
		(property "Value" "+5V"
			(at 189.23 201.93 0)
			(effects
				(font
					(size 1.27 1.27)
					(thickness 0.15)
				)
			)
		)
		(property "Footprint" ""
			(at 204.47 214.63 0)
			(effects
				(font
					(size 1.27 1.27)
					(thickness 0.15)
				)
				(justify left bottom)
				(hide yes)
			)
		)
		(property "Datasheet" ""
			(at 204.47 217.17 0)
			(effects
				(font
					(size 1.27 1.27)
					(thickness 0.15)
				)
				(justify left bottom)
				(hide yes)
			)
		)
		(property "Description" ""
			(at 189.23 207.01 0)
			(effects
				(font
					(size 1.27 1.27)
				)
				(hide yes)
			)
		)
		(property "Author" "Antmicro"
			(at 204.47 214.63 0)
			(effects
				(font
					(size 1.27 1.27)
					(thickness 0.15)
				)
				(justify left bottom)
				(hide yes)
			)
		)
		(property "License" "Apache-2.0"
			(at 204.47 217.17 0)
			(effects
				(font
					(size 1.27 1.27)
					(thickness 0.15)
				)
				(justify left bottom)
				(hide yes)
			)
		)
		(pin "1"
		)
		(instances
			(project "polarfire-som"
				(path ""
					(reference "#PWR088")
					(unit 1)
				)
			)
		)
	)
	(symbol
		(lib_id "antmicroResistors0402:R_0R_0402")
		(at 279.4 143.51 0)
		(unit 1)
		(exclude_from_sim no)
		(in_bom yes)
		(on_board yes)
		(dnp no)
		(property "Reference" "R84"
			(at 281.94 138.43 0)
			(effects
				(font
					(size 1.27 1.27)
					(thickness 0.15)
				)
			)
		)
		(property "Value" "R_0R_0402"
			(at 299.72 156.21 0)
			(effects
				(font
					(size 1.27 1.27)
					(thickness 0.15)
				)
				(justify left bottom)
				(hide yes)
			)
		)
		(property "Footprint" "antmicro-footprints:R_0402_1005Metric"
			(at 299.72 158.75 0)
			(effects
				(font
					(size 1.27 1.27)
					(thickness 0.15)
				)
				(justify left bottom)
				(hide yes)
			)
		)
		(property "Datasheet" "https://industrial.panasonic.com/cdbs/www-data/pdf/RDA0000/AOA0000C301.pdf"
			(at 299.72 161.29 0)
			(effects
				(font
					(size 1.27 1.27)
					(thickness 0.15)
				)
				(justify left bottom)
				(hide yes)
			)
		)
		(property "Description" "SMD Chip Resistor, Jumper, 0 ohm, 100 mW, 0402 [1005 Metric], Thick Film, General Purpose"
			(at 279.4 143.51 0)
			(effects
				(font
					(size 1.27 1.27)
				)
				(hide yes)
			)
		)
		(property "MPN" "ERJ2GE0R00X"
			(at 299.72 163.83 0)
			(effects
				(font
					(size 1.27 1.27)
					(thickness 0.15)
				)
				(justify left bottom)
				(hide yes)
			)
		)
		(property "Manufacturer" "Panasonic"
			(at 299.72 166.37 0)
			(effects
				(font
					(size 1.27 1.27)
					(thickness 0.15)
				)
				(justify left bottom)
				(hide yes)
			)
		)
		(property "License" "Apache-2.0"
			(at 299.72 168.91 0)
			(effects
				(font
					(size 1.27 1.27)
					(thickness 0.15)
				)
				(justify left bottom)
				(hide yes)
			)
		)
		(property "Author" "Antmicro"
			(at 299.72 171.45 0)
			(effects
				(font
					(size 1.27 1.27)
					(thickness 0.15)
				)
				(justify left bottom)
				(hide yes)
			)
		)
		(property "Val" "0R"
			(at 281.94 140.97 0)
			(effects
				(font
					(size 1.27 1.27)
					(thickness 0.15)
				)
			)
		)
		(property "Tolerance" "~"
			(at 299.72 153.67 0)
			(effects
				(font
					(size 1.27 1.27)
				)
				(justify left bottom)
				(hide yes)
			)
		)
		(property "Current" "1A"
			(at 299.72 173.99 0)
			(effects
				(font
					(size 1.27 1.27)
					(thickness 0.15)
				)
				(justify left bottom)
				(hide yes)
			)
		)
		(property "Public" ""
			(at 299.72 173.99 0)
			(effects
				(font
					(size 1.27 1.27)
				)
				(justify left bottom)
				(hide yes)
			)
		)
		(pin "1"
		)
		(pin "2"
		)
		(instances
			(project "polarfire-som"
				(path ""
					(reference "R84")
					(unit 1)
				)
			)
		)
	)
	(symbol
		(lib_id "antmicroCapacitors0402:C_10u_10V_0402")
		(at 262.89 82.55 90)
		(unit 1)
		(exclude_from_sim no)
		(in_bom yes)
		(on_board yes)
		(dnp no)
		(fields_autoplaced yes)
		(property "Reference" "C101"
			(at 265.43 78.7336 90)
			(effects
				(font
					(size 1.27 1.27)
					(thickness 0.15)
				)
				(justify right)
			)
		)
		(property "Value" "C_10u_10V_0402"
			(at 273.05 62.23 0)
			(effects
				(font
					(size 1.27 1.27)
					(thickness 0.15)
				)
				(justify left bottom)
				(hide yes)
			)
		)
		(property "Footprint" "antmicro-footprints:C_0402_1005Metric"
			(at 275.59 62.23 0)
			(effects
				(font
					(size 1.27 1.27)
					(thickness 0.15)
				)
				(justify left bottom)
				(hide yes)
			)
		)
		(property "Datasheet" "https://www.murata.com/products/productdetail?partno=GRM155R61A106ME11%23"
			(at 278.13 62.23 0)
			(effects
				(font
					(size 1.27 1.27)
					(thickness 0.15)
				)
				(justify left bottom)
				(hide yes)
			)
		)
		(property "Description" "Multilayer Ceramic Capacitors MLCC - SMD/SMT 10 uF 10 VDC 20% 0402 X5R"
			(at 262.89 82.55 0)
			(effects
				(font
					(size 1.27 1.27)
				)
				(hide yes)
			)
		)
		(property "MPN" "GRM155R61A106ME11D"
			(at 280.67 62.23 0)
			(effects
				(font
					(size 1.27 1.27)
					(thickness 0.15)
				)
				(justify left bottom)
				(hide yes)
			)
		)
		(property "Manufacturer" "Murata"
			(at 283.21 62.23 0)
			(effects
				(font
					(size 1.27 1.27)
					(thickness 0.15)
				)
				(justify left bottom)
				(hide yes)
			)
		)
		(property "License" "Apache-2.0"
			(at 285.75 62.23 0)
			(effects
				(font
					(size 1.27 1.27)
					(thickness 0.15)
				)
				(justify left bottom)
				(hide yes)
			)
		)
		(property "Author" "Antmicro"
			(at 288.29 62.23 0)
			(effects
				(font
					(size 1.27 1.27)
					(thickness 0.15)
				)
				(justify left bottom)
				(hide yes)
			)
		)
		(property "Val" "10u"
			(at 265.43 81.2736 90)
			(effects
				(font
					(size 1.27 1.27)
					(thickness 0.15)
				)
				(justify right)
			)
		)
		(property "Voltage" "10V"
			(at 290.83 62.23 0)
			(effects
				(font
					(size 1.27 1.27)
				)
				(justify left bottom)
				(hide yes)
			)
		)
		(property "Dielectric" "X5R"
			(at 293.37 62.23 0)
			(effects
				(font
					(size 1.27 1.27)
				)
				(justify left bottom)
				(hide yes)
			)
		)
		(property "Public" ""
			(at 295.91 62.23 0)
			(effects
				(font
					(size 1.27 1.27)
				)
				(justify left bottom)
				(hide yes)
			)
		)
		(pin "1"
		)
		(pin "2"
		)
		(instances
			(project "polarfire-som"
				(path ""
					(reference "C101")
					(unit 1)
				)
			)
		)
	)
	(symbol
		(lib_id "antmicroResistors0402:R_10k_0402")
		(at 354.33 140.97 90)
		(unit 1)
		(exclude_from_sim no)
		(in_bom yes)
		(on_board yes)
		(dnp no)
		(fields_autoplaced yes)
		(property "Reference" "R83"
			(at 356.235 137.1599 90)
			(effects
				(font
					(size 1.27 1.27)
					(thickness 0.15)
				)
				(justify right)
			)
		)
		(property "Value" "R_10k_0402"
			(at 367.03 120.65 0)
			(effects
				(font
					(size 1.27 1.27)
					(thickness 0.15)
				)
				(justify left bottom)
				(hide yes)
			)
		)
		(property "Footprint" "antmicro-footprints:R_0402_1005Metric"
			(at 369.57 120.65 0)
			(effects
				(font
					(size 1.27 1.27)
					(thickness 0.15)
				)
				(justify left bottom)
				(hide yes)
			)
		)
		(property "Datasheet" "https://www.bourns.com/docs/product-datasheets/cr.pdf"
			(at 372.11 120.65 0)
			(effects
				(font
					(size 1.27 1.27)
					(thickness 0.15)
				)
				(justify left bottom)
				(hide yes)
			)
		)
		(property "Description" "SMD Chip Resistor, 10 kohm, ± 1%, 62.5 mW, 0402 [1005 Metric], Thick Film, General Purpose"
			(at 354.33 140.97 0)
			(effects
				(font
					(size 1.27 1.27)
				)
				(hide yes)
			)
		)
		(property "MPN" "CR0402-FX-1002GLF"
			(at 374.65 120.65 0)
			(effects
				(font
					(size 1.27 1.27)
					(thickness 0.15)
				)
				(justify left bottom)
				(hide yes)
			)
		)
		(property "Manufacturer" "Bourns"
			(at 377.19 120.65 0)
			(effects
				(font
					(size 1.27 1.27)
					(thickness 0.15)
				)
				(justify left bottom)
				(hide yes)
			)
		)
		(property "License" "Apache-2.0"
			(at 379.73 120.65 0)
			(effects
				(font
					(size 1.27 1.27)
					(thickness 0.15)
				)
				(justify left bottom)
				(hide yes)
			)
		)
		(property "Author" "Antmicro"
			(at 382.27 120.65 0)
			(effects
				(font
					(size 1.27 1.27)
					(thickness 0.15)
				)
				(justify left bottom)
				(hide yes)
			)
		)
		(property "Val" "10k"
			(at 356.235 139.6999 90)
			(effects
				(font
					(size 1.27 1.27)
					(thickness 0.15)
				)
				(justify right)
			)
		)
		(property "Tolerance" "1%"
			(at 364.49 120.65 0)
			(effects
				(font
					(size 1.27 1.27)
				)
				(justify left bottom)
				(hide yes)
			)
		)
		(property "Public" ""
			(at 384.81 120.65 0)
			(effects
				(font
					(size 1.27 1.27)
				)
				(justify left bottom)
				(hide yes)
			)
		)
		(pin "1"
		)
		(pin "2"
		)
		(instances
			(project "polarfire-som"
				(path ""
					(reference "R83")
					(unit 1)
				)
			)
		)
	)
	(symbol
		(lib_id "antmicropower:GND")
		(at 261.62 53.34 0)
		(unit 1)
		(exclude_from_sim no)
		(in_bom yes)
		(on_board yes)
		(dnp no)
		(property "Reference" "#PWR098"
			(at 270.51 55.88 0)
			(effects
				(font
					(size 1.27 1.27)
					(thickness 0.15)
				)
				(justify left bottom)
				(hide yes)
			)
		)
		(property "Value" "GND"
			(at 261.62 57.15 0)
			(effects
				(font
					(size 1.27 1.27)
					(thickness 0.15)
				)
			)
		)
		(property "Footprint" ""
			(at 270.51 60.96 0)
			(effects
				(font
					(size 1.27 1.27)
					(thickness 0.15)
				)
				(justify left bottom)
				(hide yes)
			)
		)
		(property "Datasheet" ""
			(at 270.51 66.04 0)
			(effects
				(font
					(size 1.27 1.27)
					(thickness 0.15)
				)
				(justify left bottom)
				(hide yes)
			)
		)
		(property "Description" ""
			(at 261.62 53.34 0)
			(effects
				(font
					(size 1.27 1.27)
				)
				(hide yes)
			)
		)
		(property "Author" "Antmicro"
			(at 270.51 60.96 0)
			(effects
				(font
					(size 1.27 1.27)
					(thickness 0.15)
				)
				(justify left bottom)
				(hide yes)
			)
		)
		(property "License" "Apache-2.0"
			(at 270.51 63.5 0)
			(effects
				(font
					(size 1.27 1.27)
					(thickness 0.15)
				)
				(justify left bottom)
				(hide yes)
			)
		)
		(pin "1"
		)
		(instances
			(project "polarfire-som"
				(path ""
					(reference "#PWR098")
					(unit 1)
				)
			)
		)
	)
	(symbol
		(lib_id "antmicropower:+3V3")
		(at 299.72 44.45 0)
		(unit 1)
		(exclude_from_sim no)
		(in_bom yes)
		(on_board yes)
		(dnp no)
		(fields_autoplaced yes)
		(property "Reference" "#PWR0110"
			(at 314.96 44.45 0)
			(effects
				(font
					(size 1.27 1.27)
					(thickness 0.15)
				)
				(justify left bottom)
				(hide yes)
			)
		)
		(property "Value" "+3V3"
			(at 299.72 40.005 0)
			(effects
				(font
					(size 1.27 1.27)
					(thickness 0.15)
				)
			)
		)
		(property "Footprint" ""
			(at 314.96 52.07 0)
			(effects
				(font
					(size 1.27 1.27)
					(thickness 0.15)
				)
				(justify left bottom)
				(hide yes)
			)
		)
		(property "Datasheet" ""
			(at 314.96 54.61 0)
			(effects
				(font
					(size 1.27 1.27)
					(thickness 0.15)
				)
				(justify left bottom)
				(hide yes)
			)
		)
		(property "Description" ""
			(at 299.72 44.45 0)
			(effects
				(font
					(size 1.27 1.27)
				)
				(hide yes)
			)
		)
		(property "Author" "Antmicro"
			(at 314.96 46.99 0)
			(effects
				(font
					(size 1.27 1.27)
					(thickness 0.15)
				)
				(justify left bottom)
				(hide yes)
			)
		)
		(property "License" "Apache-2.0"
			(at 314.96 49.53 0)
			(effects
				(font
					(size 1.27 1.27)
					(thickness 0.15)
				)
				(justify left bottom)
				(hide yes)
			)
		)
		(pin "1"
		)
		(instances
			(project "polarfire-som"
				(path ""
					(reference "#PWR0110")
					(unit 1)
				)
			)
		)
	)
	(symbol
		(lib_id "antmicropower:+1V05")
		(at 311.15 212.09 0)
		(unit 1)
		(exclude_from_sim no)
		(in_bom yes)
		(on_board yes)
		(dnp no)
		(property "Reference" "#PWR0185"
			(at 311.15 215.9 0)
			(effects
				(font
					(size 1.27 1.27)
				)
				(hide yes)
			)
		)
		(property "Value" "+1V05"
			(at 311.15 207.01 0)
			(effects
				(font
					(size 1.27 1.27)
				)
			)
		)
		(property "Footprint" ""
			(at 311.15 212.09 0)
			(effects
				(font
					(size 1.27 1.27)
				)
				(hide yes)
			)
		)
		(property "Datasheet" ""
			(at 311.15 212.09 0)
			(effects
				(font
					(size 1.27 1.27)
				)
				(hide yes)
			)
		)
		(property "Description" ""
			(at 311.15 212.09 0)
			(effects
				(font
					(size 1.27 1.27)
				)
				(hide yes)
			)
		)
		(pin "1"
		)
		(instances
			(project "polarfire-som"
				(path ""
					(reference "#PWR0185")
					(unit 1)
				)
			)
		)
	)
	(symbol
		(lib_id "antmicroCapacitors0402:C_22u_0402")
		(at 173.99 74.93 90)
		(unit 1)
		(exclude_from_sim no)
		(in_bom yes)
		(on_board yes)
		(dnp no)
		(fields_autoplaced yes)
		(property "Reference" "C86"
			(at 176.53 71.1136 90)
			(effects
				(font
					(size 1.27 1.27)
					(thickness 0.15)
				)
				(justify right)
			)
		)
		(property "Value" "C_22u_0402"
			(at 184.15 54.61 0)
			(effects
				(font
					(size 1.27 1.27)
					(thickness 0.15)
				)
				(justify left bottom)
				(hide yes)
			)
		)
		(property "Footprint" "antmicro-footprints:C_0402_1005Metric"
			(at 186.69 54.61 0)
			(effects
				(font
					(size 1.27 1.27)
					(thickness 0.15)
				)
				(justify left bottom)
				(hide yes)
			)
		)
		(property "Datasheet" "https://www.murata.com/products/productdetail?partno=GRM158R60J226ME01%23"
			(at 189.23 54.61 0)
			(effects
				(font
					(size 1.27 1.27)
					(thickness 0.15)
				)
				(justify left bottom)
				(hide yes)
			)
		)
		(property "Description" "SMD Multilayer Ceramic Capacitor, 22 uF, 4 V, 0402 [1005 Metric], X6S"
			(at 173.99 74.93 0)
			(effects
				(font
					(size 1.27 1.27)
				)
				(hide yes)
			)
		)
		(property "MPN" "GRM158R60J226ME01D"
			(at 191.77 54.61 0)
			(effects
				(font
					(size 1.27 1.27)
					(thickness 0.15)
				)
				(justify left bottom)
				(hide yes)
			)
		)
		(property "Manufacturer" "Murata"
			(at 194.31 54.61 0)
			(effects
				(font
					(size 1.27 1.27)
					(thickness 0.15)
				)
				(justify left bottom)
				(hide yes)
			)
		)
		(property "License" "Apache-2.0"
			(at 196.85 54.61 0)
			(effects
				(font
					(size 1.27 1.27)
					(thickness 0.15)
				)
				(justify left bottom)
				(hide yes)
			)
		)
		(property "Author" "Antmicro"
			(at 199.39 54.61 0)
			(effects
				(font
					(size 1.27 1.27)
					(thickness 0.15)
				)
				(justify left bottom)
				(hide yes)
			)
		)
		(property "Val" "22u"
			(at 176.53 73.6536 90)
			(effects
				(font
					(size 1.27 1.27)
					(thickness 0.15)
				)
				(justify right)
			)
		)
		(property "Voltage" ""
			(at 201.93 54.61 0)
			(effects
				(font
					(size 1.27 1.27)
				)
				(justify left bottom)
				(hide yes)
			)
		)
		(property "Dielectric" ""
			(at 204.47 54.61 0)
			(effects
				(font
					(size 1.27 1.27)
				)
				(justify left bottom)
				(hide yes)
			)
		)
		(property "Public" ""
			(at 207.01 54.61 0)
			(effects
				(font
					(size 1.27 1.27)
				)
				(justify left bottom)
				(hide yes)
			)
		)
		(pin "2"
		)
		(pin "1"
		)
		(instances
			(project "polarfire-som"
				(path ""
					(reference "C86")
					(unit 1)
				)
			)
		)
	)
	(symbol
		(lib_id "antmicropower:+5V")
		(at 63.5 127 0)
		(unit 1)
		(exclude_from_sim no)
		(in_bom yes)
		(on_board yes)
		(dnp no)
		(property "Reference" "#PWR068"
			(at 78.74 129.54 0)
			(effects
				(font
					(size 1.27 1.27)
					(thickness 0.15)
				)
				(justify left bottom)
				(hide yes)
			)
		)
		(property "Value" "+5V"
			(at 63.5 123.19 0)
			(effects
				(font
					(size 1.27 1.27)
					(thickness 0.15)
				)
			)
		)
		(property "Footprint" ""
			(at 78.74 134.62 0)
			(effects
				(font
					(size 1.27 1.27)
					(thickness 0.15)
				)
				(justify left bottom)
				(hide yes)
			)
		)
		(property "Datasheet" ""
			(at 78.74 137.16 0)
			(effects
				(font
					(size 1.27 1.27)
					(thickness 0.15)
				)
				(justify left bottom)
				(hide yes)
			)
		)
		(property "Description" ""
			(at 63.5 127 0)
			(effects
				(font
					(size 1.27 1.27)
				)
				(hide yes)
			)
		)
		(property "Author" "Antmicro"
			(at 78.74 134.62 0)
			(effects
				(font
					(size 1.27 1.27)
					(thickness 0.15)
				)
				(justify left bottom)
				(hide yes)
			)
		)
		(property "License" "Apache-2.0"
			(at 78.74 137.16 0)
			(effects
				(font
					(size 1.27 1.27)
					(thickness 0.15)
				)
				(justify left bottom)
				(hide yes)
			)
		)
		(pin "1"
		)
		(instances
			(project "polarfire-som"
				(path ""
					(reference "#PWR068")
					(unit 1)
				)
			)
		)
	)
	(symbol
		(lib_id "antmicroResistors0402:R_100k_0402")
		(at 354.33 151.13 90)
		(unit 1)
		(exclude_from_sim no)
		(in_bom yes)
		(on_board yes)
		(dnp no)
		(property "Reference" "R69"
			(at 355.6 147.32 90)
			(effects
				(font
					(size 1.27 1.27)
					(thickness 0.15)
				)
				(justify right)
			)
		)
		(property "Value" "R_100k_0402"
			(at 367.03 130.81 0)
			(effects
				(font
					(size 1.27 1.27)
					(thickness 0.15)
				)
				(justify left bottom)
				(hide yes)
			)
		)
		(property "Footprint" "antmicro-footprints:R_0402_1005Metric"
			(at 369.57 130.81 0)
			(effects
				(font
					(size 1.27 1.27)
					(thickness 0.15)
				)
				(justify left bottom)
				(hide yes)
			)
		)
		(property "Datasheet" "https://www.bourns.com/docs/product-datasheets/cr.pdf"
			(at 372.11 130.81 0)
			(effects
				(font
					(size 1.27 1.27)
					(thickness 0.15)
				)
				(justify left bottom)
				(hide yes)
			)
		)
		(property "Description" "SMD Chip Resistor, 100 kohm, ± 1%, 62.5 mW, 0402 [1005 Metric], Thick Film, General Purpose"
			(at 354.33 151.13 0)
			(effects
				(font
					(size 1.27 1.27)
				)
				(hide yes)
			)
		)
		(property "MPN" "CR0402-FX-1003GLF"
			(at 374.65 130.81 0)
			(effects
				(font
					(size 1.27 1.27)
					(thickness 0.15)
				)
				(justify left bottom)
				(hide yes)
			)
		)
		(property "Manufacturer" "Bourns"
			(at 377.19 130.81 0)
			(effects
				(font
					(size 1.27 1.27)
					(thickness 0.15)
				)
				(justify left bottom)
				(hide yes)
			)
		)
		(property "License" "Apache-2.0"
			(at 379.73 130.81 0)
			(effects
				(font
					(size 1.27 1.27)
					(thickness 0.15)
				)
				(justify left bottom)
				(hide yes)
			)
		)
		(property "Author" "Antmicro"
			(at 382.27 130.81 0)
			(effects
				(font
					(size 1.27 1.27)
					(thickness 0.15)
				)
				(justify left bottom)
				(hide yes)
			)
		)
		(property "Val" "100k"
			(at 355.6 149.86 90)
			(effects
				(font
					(size 1.27 1.27)
					(thickness 0.15)
				)
				(justify right)
			)
		)
		(property "Tolerance" "1%"
			(at 364.49 130.81 0)
			(effects
				(font
					(size 1.27 1.27)
				)
				(justify left bottom)
				(hide yes)
			)
		)
		(property "Public" ""
			(at 384.81 130.81 0)
			(effects
				(font
					(size 1.27 1.27)
				)
				(justify left bottom)
				(hide yes)
			)
		)
		(pin "1"
		)
		(pin "2"
		)
		(instances
			(project "polarfire-som"
				(path ""
					(reference "R69")
					(unit 1)
				)
			)
		)
	)
	(symbol
		(lib_id "antmicropower:GND")
		(at 262.89 134.62 0)
		(unit 1)
		(exclude_from_sim no)
		(in_bom yes)
		(on_board yes)
		(dnp no)
		(property "Reference" "#PWR0103"
			(at 271.78 137.16 0)
			(effects
				(font
					(size 1.27 1.27)
					(thickness 0.15)
				)
				(justify left bottom)
				(hide yes)
			)
		)
		(property "Value" "GND"
			(at 262.89 139.7 0)
			(effects
				(font
					(size 1.27 1.27)
					(thickness 0.15)
				)
			)
		)
		(property "Footprint" ""
			(at 271.78 142.24 0)
			(effects
				(font
					(size 1.27 1.27)
					(thickness 0.15)
				)
				(justify left bottom)
				(hide yes)
			)
		)
		(property "Datasheet" ""
			(at 271.78 147.32 0)
			(effects
				(font
					(size 1.27 1.27)
					(thickness 0.15)
				)
				(justify left bottom)
				(hide yes)
			)
		)
		(property "Description" ""
			(at 262.89 134.62 0)
			(effects
				(font
					(size 1.27 1.27)
				)
				(hide yes)
			)
		)
		(property "Author" "Antmicro"
			(at 271.78 142.24 0)
			(effects
				(font
					(size 1.27 1.27)
					(thickness 0.15)
				)
				(justify left bottom)
				(hide yes)
			)
		)
		(property "License" "Apache-2.0"
			(at 271.78 144.78 0)
			(effects
				(font
					(size 1.27 1.27)
					(thickness 0.15)
				)
				(justify left bottom)
				(hide yes)
			)
		)
		(pin "1"
		)
		(instances
			(project "polarfire-som"
				(path ""
					(reference "#PWR0103")
					(unit 1)
				)
			)
		)
	)
	(symbol
		(lib_id "antmicropower:GND")
		(at 261.62 100.33 0)
		(unit 1)
		(exclude_from_sim no)
		(in_bom yes)
		(on_board yes)
		(dnp no)
		(fields_autoplaced yes)
		(property "Reference" "#PWR0101"
			(at 270.51 102.87 0)
			(effects
				(font
					(size 1.27 1.27)
					(thickness 0.15)
				)
				(justify left bottom)
				(hide yes)
			)
		)
		(property "Value" "GND"
			(at 261.62 105.41 0)
			(effects
				(font
					(size 1.27 1.27)
					(thickness 0.15)
				)
			)
		)
		(property "Footprint" ""
			(at 270.51 107.95 0)
			(effects
				(font
					(size 1.27 1.27)
					(thickness 0.15)
				)
				(justify left bottom)
				(hide yes)
			)
		)
		(property "Datasheet" ""
			(at 270.51 113.03 0)
			(effects
				(font
					(size 1.27 1.27)
					(thickness 0.15)
				)
				(justify left bottom)
				(hide yes)
			)
		)
		(property "Description" ""
			(at 261.62 100.33 0)
			(effects
				(font
					(size 1.27 1.27)
				)
				(hide yes)
			)
		)
		(property "Author" "Antmicro"
			(at 270.51 107.95 0)
			(effects
				(font
					(size 1.27 1.27)
					(thickness 0.15)
				)
				(justify left bottom)
				(hide yes)
			)
		)
		(property "License" "Apache-2.0"
			(at 270.51 110.49 0)
			(effects
				(font
					(size 1.27 1.27)
					(thickness 0.15)
				)
				(justify left bottom)
				(hide yes)
			)
		)
		(pin "1"
		)
		(instances
			(project "polarfire-som"
				(path ""
					(reference "#PWR0101")
					(unit 1)
				)
			)
		)
	)
	(symbol
		(lib_id "antmicroFixedInductors:L_1u5_2.8A_0806")
		(at 248.92 60.96 0)
		(unit 1)
		(exclude_from_sim no)
		(in_bom yes)
		(on_board yes)
		(dnp no)
		(fields_autoplaced yes)
		(property "Reference" "L3"
			(at 251.46 55.88 0)
			(effects
				(font
					(size 1.27 1.27)
					(thickness 0.15)
				)
			)
		)
		(property "Value" "L_1u5_2.8A_0806"
			(at 262.89 63.5 0)
			(effects
				(font
					(size 1.27 1.27)
					(thickness 0.15)
				)
				(justify left bottom)
				(hide yes)
			)
		)
		(property "Footprint" "antmicro-footprints:L_0806_2016Metric"
			(at 262.89 68.58 0)
			(effects
				(font
					(size 1.27 1.27)
					(thickness 0.15)
				)
				(justify left bottom)
				(hide yes)
			)
		)
		(property "Datasheet" "https://abracon.com/datasheets/AOTA-B201610S.pdf"
			(at 262.89 71.12 0)
			(effects
				(font
					(size 1.27 1.27)
					(thickness 0.15)
				)
				(justify left bottom)
				(hide yes)
			)
		)
		(property "Description" "Power Inductor (SMT), 1.5 µH, 0.074 ohm, 2.8 A, AOTA-B201610S"
			(at 248.92 60.96 0)
			(effects
				(font
					(size 1.27 1.27)
				)
				(hide yes)
			)
		)
		(property "Val" "1.5u/2.8A"
			(at 251.46 58.42 0)
			(effects
				(font
					(size 1.27 1.27)
					(thickness 0.15)
				)
			)
		)
		(property "Manufacturer" "Abracon"
			(at 262.89 73.66 0)
			(effects
				(font
					(size 1.27 1.27)
					(thickness 0.15)
				)
				(justify left bottom)
				(hide yes)
			)
		)
		(property "MPN" "AOTA-B201610S1R5MT"
			(at 262.89 76.2 0)
			(effects
				(font
					(size 1.27 1.27)
					(thickness 0.15)
				)
				(justify left bottom)
				(hide yes)
			)
		)
		(property "ISat" "3.5 A"
			(at 262.89 77.47 0)
			(effects
				(font
					(size 1.27 1.27)
				)
				(justify left)
				(hide yes)
			)
		)
		(property "IMax" "2.8 A"
			(at 262.89 81.28 0)
			(effects
				(font
					(size 1.27 1.27)
					(thickness 0.15)
				)
				(justify left bottom)
				(hide yes)
			)
		)
		(property "Size" "2.0x1.6"
			(at 262.89 83.82 0)
			(effects
				(font
					(size 1.27 1.27)
					(thickness 0.15)
				)
				(justify left bottom)
				(hide yes)
			)
		)
		(property "Author" "Antmicro"
			(at 262.89 86.36 0)
			(effects
				(font
					(size 1.27 1.27)
					(thickness 0.15)
				)
				(justify left bottom)
				(hide yes)
			)
		)
		(property "License" "Apache-2.0"
			(at 262.89 88.9 0)
			(effects
				(font
					(size 1.27 1.27)
					(thickness 0.15)
				)
				(justify left bottom)
				(hide yes)
			)
		)
		(property "Public" ""
			(at 262.89 91.44 0)
			(effects
				(font
					(size 1.27 1.27)
				)
				(justify left bottom)
				(hide yes)
			)
		)
		(pin "1"
		)
		(pin "2"
		)
		(instances
			(project "polarfire-som"
				(path ""
					(reference "L3")
					(unit 1)
				)
			)
		)
	)
	(symbol
		(lib_id "antmicroCapacitors0402:C_10u_10V_0402")
		(at 262.89 133.35 90)
		(unit 1)
		(exclude_from_sim no)
		(in_bom yes)
		(on_board yes)
		(dnp no)
		(fields_autoplaced yes)
		(property "Reference" "C104"
			(at 265.43 129.5336 90)
			(effects
				(font
					(size 1.27 1.27)
					(thickness 0.15)
				)
				(justify right)
			)
		)
		(property "Value" "C_10u_10V_0402"
			(at 273.05 113.03 0)
			(effects
				(font
					(size 1.27 1.27)
					(thickness 0.15)
				)
				(justify left bottom)
				(hide yes)
			)
		)
		(property "Footprint" "antmicro-footprints:C_0402_1005Metric"
			(at 275.59 113.03 0)
			(effects
				(font
					(size 1.27 1.27)
					(thickness 0.15)
				)
				(justify left bottom)
				(hide yes)
			)
		)
		(property "Datasheet" "https://www.murata.com/products/productdetail?partno=GRM155R61A106ME11%23"
			(at 278.13 113.03 0)
			(effects
				(font
					(size 1.27 1.27)
					(thickness 0.15)
				)
				(justify left bottom)
				(hide yes)
			)
		)
		(property "Description" "Multilayer Ceramic Capacitors MLCC - SMD/SMT 10 uF 10 VDC 20% 0402 X5R"
			(at 262.89 133.35 0)
			(effects
				(font
					(size 1.27 1.27)
				)
				(hide yes)
			)
		)
		(property "MPN" "GRM155R61A106ME11D"
			(at 280.67 113.03 0)
			(effects
				(font
					(size 1.27 1.27)
					(thickness 0.15)
				)
				(justify left bottom)
				(hide yes)
			)
		)
		(property "Manufacturer" "Murata"
			(at 283.21 113.03 0)
			(effects
				(font
					(size 1.27 1.27)
					(thickness 0.15)
				)
				(justify left bottom)
				(hide yes)
			)
		)
		(property "License" "Apache-2.0"
			(at 285.75 113.03 0)
			(effects
				(font
					(size 1.27 1.27)
					(thickness 0.15)
				)
				(justify left bottom)
				(hide yes)
			)
		)
		(property "Author" "Antmicro"
			(at 288.29 113.03 0)
			(effects
				(font
					(size 1.27 1.27)
					(thickness 0.15)
				)
				(justify left bottom)
				(hide yes)
			)
		)
		(property "Val" "10u"
			(at 265.43 132.0736 90)
			(effects
				(font
					(size 1.27 1.27)
					(thickness 0.15)
				)
				(justify right)
			)
		)
		(property "Voltage" "10V"
			(at 290.83 113.03 0)
			(effects
				(font
					(size 1.27 1.27)
				)
				(justify left bottom)
				(hide yes)
			)
		)
		(property "Dielectric" "X5R"
			(at 293.37 113.03 0)
			(effects
				(font
					(size 1.27 1.27)
				)
				(justify left bottom)
				(hide yes)
			)
		)
		(property "Public" ""
			(at 295.91 113.03 0)
			(effects
				(font
					(size 1.27 1.27)
				)
				(justify left bottom)
				(hide yes)
			)
		)
		(pin "1"
		)
		(pin "2"
		)
		(instances
			(project "polarfire-som"
				(path ""
					(reference "C104")
					(unit 1)
				)
			)
		)
	)
	(symbol
		(lib_id "antmicroPowerMeasurement:PAC1934T_WLCSP")
		(at 66.04 49.53 0)
		(unit 1)
		(exclude_from_sim no)
		(in_bom yes)
		(on_board yes)
		(dnp no)
		(fields_autoplaced yes)
		(property "Reference" "U6"
			(at 80.01 41.91 0)
			(effects
				(font
					(size 1.27 1.27)
					(thickness 0.15)
				)
			)
		)
		(property "Value" "PAC1934T_WLCSP"
			(at 116.84 57.15 0)
			(effects
				(font
					(size 1.27 1.27)
					(thickness 0.15)
				)
				(justify left bottom)
				(hide yes)
			)
		)
		(property "Footprint" "antmicro-footprints:WLCSP-16_2.25x2.17x0.68mm_Layout4x4_P0.5x0.5mm"
			(at 116.84 59.69 0)
			(effects
				(font
					(size 1.27 1.27)
					(thickness 0.15)
				)
				(justify left bottom)
				(hide yes)
			)
		)
		(property "Datasheet" "https://www.mouser.com/datasheet/2/268/PAC1931_Family_Data_Sheet_DS20005850E-1519053.pdf"
			(at 116.84 62.23 0)
			(effects
				(font
					(size 1.27 1.27)
					(thickness 0.15)
				)
				(justify left bottom)
				(hide yes)
			)
		)
		(property "Description" "DC Power/Energy Monitor With Accumulator, Quad High-side current Sensor, 2.7V to 5.5V, WLCSP-16"
			(at 66.04 49.53 0)
			(effects
				(font
					(size 1.27 1.27)
				)
				(hide yes)
			)
		)
		(property "Manufacturer" "Microchip Technology"
			(at 116.84 64.77 0)
			(effects
				(font
					(size 1.27 1.27)
					(thickness 0.15)
				)
				(justify left bottom)
				(hide yes)
			)
		)
		(property "MPN" "PAC1934T-I/J6CX"
			(at 80.01 44.45 0)
			(effects
				(font
					(size 1.27 1.27)
					(thickness 0.15)
				)
			)
		)
		(property "Author" "Antmicro"
			(at 116.84 67.31 0)
			(effects
				(font
					(size 1.27 1.27)
					(thickness 0.15)
				)
				(justify left bottom)
				(hide yes)
			)
		)
		(property "License" "Apache-2.0"
			(at 116.84 69.85 0)
			(effects
				(font
					(size 1.27 1.27)
					(thickness 0.15)
				)
				(justify left bottom)
				(hide yes)
			)
		)
		(pin "B2"
		)
		(pin "B4"
		)
		(pin "C3"
		)
		(pin "C1"
		)
		(pin "A2"
		)
		(pin "B3"
		)
		(pin "D3"
		)
		(pin "D4"
		)
		(pin "D2"
		)
		(pin "A1"
		)
		(pin "A4"
		)
		(pin "D1"
		)
		(pin "B1"
		)
		(pin "C2"
		)
		(pin "A3"
		)
		(pin "C4"
		)
		(instances
			(project "polarfire-som"
				(path ""
					(reference "U6")
					(unit 1)
				)
			)
		)
	)
	(symbol
		(lib_id "antmicroResistors0402:R_0R_0402")
		(at 55.88 71.12 90)
		(unit 1)
		(exclude_from_sim no)
		(in_bom yes)
		(on_board yes)
		(dnp no)
		(fields_autoplaced yes)
		(property "Reference" "R4"
			(at 57.785 67.3099 90)
			(effects
				(font
					(size 1.27 1.27)
					(thickness 0.15)
				)
				(justify right)
			)
		)
		(property "Value" "R_0R_0402"
			(at 68.58 50.8 0)
			(effects
				(font
					(size 1.27 1.27)
					(thickness 0.15)
				)
				(justify left bottom)
				(hide yes)
			)
		)
		(property "Footprint" "antmicro-footprints:R_0402_1005Metric"
			(at 71.12 50.8 0)
			(effects
				(font
					(size 1.27 1.27)
					(thickness 0.15)
				)
				(justify left bottom)
				(hide yes)
			)
		)
		(property "Datasheet" "https://industrial.panasonic.com/cdbs/www-data/pdf/RDA0000/AOA0000C301.pdf"
			(at 73.66 50.8 0)
			(effects
				(font
					(size 1.27 1.27)
					(thickness 0.15)
				)
				(justify left bottom)
				(hide yes)
			)
		)
		(property "Description" "SMD Chip Resistor, Jumper, 0 ohm, 100 mW, 0402 [1005 Metric], Thick Film, General Purpose"
			(at 55.88 71.12 0)
			(effects
				(font
					(size 1.27 1.27)
				)
				(hide yes)
			)
		)
		(property "MPN" "ERJ2GE0R00X"
			(at 76.2 50.8 0)
			(effects
				(font
					(size 1.27 1.27)
					(thickness 0.15)
				)
				(justify left bottom)
				(hide yes)
			)
		)
		(property "Manufacturer" "Panasonic"
			(at 78.74 50.8 0)
			(effects
				(font
					(size 1.27 1.27)
					(thickness 0.15)
				)
				(justify left bottom)
				(hide yes)
			)
		)
		(property "License" "Apache-2.0"
			(at 81.28 50.8 0)
			(effects
				(font
					(size 1.27 1.27)
					(thickness 0.15)
				)
				(justify left bottom)
				(hide yes)
			)
		)
		(property "Author" "Antmicro"
			(at 83.82 50.8 0)
			(effects
				(font
					(size 1.27 1.27)
					(thickness 0.15)
				)
				(justify left bottom)
				(hide yes)
			)
		)
		(property "Val" "0R"
			(at 57.785 69.8499 90)
			(effects
				(font
					(size 1.27 1.27)
					(thickness 0.15)
				)
				(justify right)
			)
		)
		(property "Tolerance" "~"
			(at 66.04 50.8 0)
			(effects
				(font
					(size 1.27 1.27)
				)
				(justify left bottom)
				(hide yes)
			)
		)
		(property "Current" "1A"
			(at 86.36 50.8 0)
			(effects
				(font
					(size 1.27 1.27)
					(thickness 0.15)
				)
				(justify left bottom)
				(hide yes)
			)
		)
		(property "Public" ""
			(at 86.36 50.8 0)
			(effects
				(font
					(size 1.27 1.27)
				)
				(justify left bottom)
				(hide yes)
			)
		)
		(pin "1"
		)
		(pin "2"
		)
		(instances
			(project "polarfire-som"
				(path ""
					(reference "R4")
					(unit 1)
				)
			)
		)
	)
	(symbol
		(lib_id "antmicroResistors0402:R_10k_0402")
		(at 60.96 62.23 180)
		(unit 1)
		(exclude_from_sim no)
		(in_bom yes)
		(on_board yes)
		(dnp no)
		(property "Reference" "R6"
			(at 55.88 63.5 0)
			(effects
				(font
					(size 1.27 1.27)
					(thickness 0.15)
				)
				(justify left)
			)
		)
		(property "Value" "R_10k_0402"
			(at 40.64 49.53 0)
			(effects
				(font
					(size 1.27 1.27)
					(thickness 0.15)
				)
				(justify left bottom)
				(hide yes)
			)
		)
		(property "Footprint" "antmicro-footprints:R_0402_1005Metric"
			(at 40.64 46.99 0)
			(effects
				(font
					(size 1.27 1.27)
					(thickness 0.15)
				)
				(justify left bottom)
				(hide yes)
			)
		)
		(property "Datasheet" "https://www.bourns.com/docs/product-datasheets/cr.pdf"
			(at 40.64 44.45 0)
			(effects
				(font
					(size 1.27 1.27)
					(thickness 0.15)
				)
				(justify left bottom)
				(hide yes)
			)
		)
		(property "Description" "SMD Chip Resistor, 10 kohm, ± 1%, 62.5 mW, 0402 [1005 Metric], Thick Film, General Purpose"
			(at 60.96 62.23 0)
			(effects
				(font
					(size 1.27 1.27)
				)
				(hide yes)
			)
		)
		(property "MPN" "CR0402-FX-1002GLF"
			(at 40.64 41.91 0)
			(effects
				(font
					(size 1.27 1.27)
					(thickness 0.15)
				)
				(justify left bottom)
				(hide yes)
			)
		)
		(property "Manufacturer" "Bourns"
			(at 40.64 39.37 0)
			(effects
				(font
					(size 1.27 1.27)
					(thickness 0.15)
				)
				(justify left bottom)
				(hide yes)
			)
		)
		(property "License" "Apache-2.0"
			(at 40.64 36.83 0)
			(effects
				(font
					(size 1.27 1.27)
					(thickness 0.15)
				)
				(justify left bottom)
				(hide yes)
			)
		)
		(property "Author" "Antmicro"
			(at 40.64 34.29 0)
			(effects
				(font
					(size 1.27 1.27)
					(thickness 0.15)
				)
				(justify left bottom)
				(hide yes)
			)
		)
		(property "Val" "10k"
			(at 60.96 63.5 0)
			(effects
				(font
					(size 1.27 1.27)
					(thickness 0.15)
				)
				(justify right)
			)
		)
		(property "Tolerance" "1%"
			(at 40.64 52.07 0)
			(effects
				(font
					(size 1.27 1.27)
				)
				(justify left bottom)
				(hide yes)
			)
		)
		(property "Public" ""
			(at 40.64 31.75 0)
			(effects
				(font
					(size 1.27 1.27)
				)
				(justify left bottom)
				(hide yes)
			)
		)
		(pin "1"
		)
		(pin "2"
		)
		(instances
			(project "polarfire-som"
				(path ""
					(reference "R6")
					(unit 1)
				)
			)
		)
	)
	(symbol
		(lib_id "antmicroResistors0603:R_0R01_0603")
		(at 289.56 60.96 0)
		(unit 1)
		(exclude_from_sim no)
		(in_bom yes)
		(on_board yes)
		(dnp no)
		(fields_autoplaced yes)
		(property "Reference" "R47"
			(at 292.1 54.61 0)
			(effects
				(font
					(size 1.27 1.27)
					(thickness 0.15)
				)
			)
		)
		(property "Value" "R_0R01_0603"
			(at 309.88 73.66 0)
			(effects
				(font
					(size 1.27 1.27)
					(thickness 0.15)
				)
				(justify left bottom)
				(hide yes)
			)
		)
		(property "Footprint" "antmicro-footprints:R_0603_1608Metric"
			(at 309.88 76.2 0)
			(effects
				(font
					(size 1.27 1.27)
					(thickness 0.15)
				)
				(justify left bottom)
				(hide yes)
			)
		)
		(property "Datasheet" "https://www.bourns.com/docs/product-datasheets/cfn-a.pdf"
			(at 309.88 78.74 0)
			(effects
				(font
					(size 1.27 1.27)
					(thickness 0.15)
				)
				(justify left bottom)
				(hide yes)
			)
		)
		(property "Description" "SMD Chip Resistor, 10 mohm, ± 1%, 0.5 W, 0603 [1608 Metric], Metal Foil, Current Sensing"
			(at 289.56 60.96 0)
			(effects
				(font
					(size 1.27 1.27)
				)
				(hide yes)
			)
		)
		(property "MPN" "CFN0603AFZ-R010ELF"
			(at 309.88 81.28 0)
			(effects
				(font
					(size 1.27 1.27)
					(thickness 0.15)
				)
				(justify left bottom)
				(hide yes)
			)
		)
		(property "Manufacturer" "Bourns"
			(at 309.88 83.82 0)
			(effects
				(font
					(size 1.27 1.27)
					(thickness 0.15)
				)
				(justify left bottom)
				(hide yes)
			)
		)
		(property "License" "Apache-2.0"
			(at 309.88 86.36 0)
			(effects
				(font
					(size 1.27 1.27)
					(thickness 0.15)
				)
				(justify left bottom)
				(hide yes)
			)
		)
		(property "Author" "Antmicro"
			(at 309.88 88.9 0)
			(effects
				(font
					(size 1.27 1.27)
					(thickness 0.15)
				)
				(justify left bottom)
				(hide yes)
			)
		)
		(property "Val" "0R01"
			(at 292.1 57.15 0)
			(effects
				(font
					(size 1.27 1.27)
					(thickness 0.15)
				)
			)
		)
		(property "Tolerance" "1%"
			(at 309.88 71.12 0)
			(effects
				(font
					(size 1.27 1.27)
				)
				(justify left bottom)
				(hide yes)
			)
		)
		(property "Public" ""
			(at 309.88 91.44 0)
			(effects
				(font
					(size 1.27 1.27)
				)
				(justify left bottom)
				(hide yes)
			)
		)
		(pin "1"
		)
		(pin "2"
		)
		(instances
			(project "polarfire-som"
				(path ""
					(reference "R47")
					(unit 1)
				)
			)
		)
	)
	(symbol
		(lib_id "antmicroTestPoints:TP_0.75mm_SMD")
		(at 158.75 129.54 180)
		(unit 1)
		(exclude_from_sim no)
		(in_bom no)
		(on_board yes)
		(dnp no)
		(property "Reference" "TP26"
			(at 151.765 129.54 0)
			(effects
				(font
					(size 1.27 1.27)
					(thickness 0.15)
				)
			)
		)
		(property "Value" "TP_0.75mm_SMD"
			(at 147.955 125.73 0)
			(effects
				(font
					(size 1.27 1.27)
					(thickness 0.15)
				)
				(justify left bottom)
				(hide yes)
			)
		)
		(property "Footprint" "antmicro-footprints:TP_SMD_0.75mm"
			(at 147.955 123.19 0)
			(effects
				(font
					(size 1.27 1.27)
					(thickness 0.15)
				)
				(justify left bottom)
				(hide yes)
			)
		)
		(property "Datasheet" ""
			(at 140.97 116.84 0)
			(effects
				(font
					(size 1.27 1.27)
					(thickness 0.15)
				)
				(justify left bottom)
				(hide yes)
			)
		)
		(property "Description" "SMT test point"
			(at 158.75 129.54 0)
			(effects
				(font
					(size 1.27 1.27)
				)
				(hide yes)
			)
		)
		(property "MPN" ""
			(at 147.955 118.11 0)
			(effects
				(font
					(size 1.27 1.27)
					(thickness 0.15)
				)
				(justify left bottom)
				(hide yes)
			)
		)
		(property "Manufacturer" ""
			(at 147.955 123.19 0)
			(effects
				(font
					(size 1.27 1.27)
					(thickness 0.15)
				)
				(justify left bottom)
				(hide yes)
			)
		)
		(property "Author" "Antmicro"
			(at 147.955 120.65 0)
			(effects
				(font
					(size 1.27 1.27)
					(thickness 0.15)
				)
				(justify left bottom)
				(hide yes)
			)
		)
		(property "License" "Apache-2.0"
			(at 147.955 118.11 0)
			(effects
				(font
					(size 1.27 1.27)
					(thickness 0.15)
				)
				(justify left bottom)
				(hide yes)
			)
		)
		(property "Public" "False"
			(at 148.59 115.57 0)
			(effects
				(font
					(size 1.27 1.27)
				)
				(justify left bottom)
				(hide yes)
			)
		)
		(pin "1"
		)
		(instances
			(project "polarfire-som"
				(path ""
					(reference "TP26")
					(unit 1)
				)
			)
		)
	)
	(symbol
		(lib_id "antmicropower:GND")
		(at 270.51 53.34 0)
		(unit 1)
		(exclude_from_sim no)
		(in_bom yes)
		(on_board yes)
		(dnp no)
		(property "Reference" "#PWR0104"
			(at 279.4 55.88 0)
			(effects
				(font
					(size 1.27 1.27)
					(thickness 0.15)
				)
				(justify left bottom)
				(hide yes)
			)
		)
		(property "Value" "GND"
			(at 270.51 57.15 0)
			(effects
				(font
					(size 1.27 1.27)
					(thickness 0.15)
				)
			)
		)
		(property "Footprint" ""
			(at 279.4 60.96 0)
			(effects
				(font
					(size 1.27 1.27)
					(thickness 0.15)
				)
				(justify left bottom)
				(hide yes)
			)
		)
		(property "Datasheet" ""
			(at 279.4 66.04 0)
			(effects
				(font
					(size 1.27 1.27)
					(thickness 0.15)
				)
				(justify left bottom)
				(hide yes)
			)
		)
		(property "Description" ""
			(at 270.51 53.34 0)
			(effects
				(font
					(size 1.27 1.27)
				)
				(hide yes)
			)
		)
		(property "Author" "Antmicro"
			(at 279.4 60.96 0)
			(effects
				(font
					(size 1.27 1.27)
					(thickness 0.15)
				)
				(justify left bottom)
				(hide yes)
			)
		)
		(property "License" "Apache-2.0"
			(at 279.4 63.5 0)
			(effects
				(font
					(size 1.27 1.27)
					(thickness 0.15)
				)
				(justify left bottom)
				(hide yes)
			)
		)
		(pin "1"
		)
		(instances
			(project "polarfire-som"
				(path ""
					(reference "#PWR0104")
					(unit 1)
				)
			)
		)
	)
	(symbol
		(lib_id "antmicroCapacitors0402:C_22u_0402")
		(at 271.78 116.84 90)
		(unit 1)
		(exclude_from_sim no)
		(in_bom yes)
		(on_board yes)
		(dnp no)
		(fields_autoplaced yes)
		(property "Reference" "C109"
			(at 274.32 113.0236 90)
			(effects
				(font
					(size 1.27 1.27)
					(thickness 0.15)
				)
				(justify right)
			)
		)
		(property "Value" "C_22u_0402"
			(at 281.94 96.52 0)
			(effects
				(font
					(size 1.27 1.27)
					(thickness 0.15)
				)
				(justify left bottom)
				(hide yes)
			)
		)
		(property "Footprint" "antmicro-footprints:C_0402_1005Metric"
			(at 284.48 96.52 0)
			(effects
				(font
					(size 1.27 1.27)
					(thickness 0.15)
				)
				(justify left bottom)
				(hide yes)
			)
		)
		(property "Datasheet" "https://www.murata.com/products/productdetail?partno=GRM158R60J226ME01%23"
			(at 287.02 96.52 0)
			(effects
				(font
					(size 1.27 1.27)
					(thickness 0.15)
				)
				(justify left bottom)
				(hide yes)
			)
		)
		(property "Description" "SMD Multilayer Ceramic Capacitor, 22 uF, 4 V, 0402 [1005 Metric], X6S"
			(at 271.78 116.84 0)
			(effects
				(font
					(size 1.27 1.27)
				)
				(hide yes)
			)
		)
		(property "MPN" "GRM158R60J226ME01D"
			(at 289.56 96.52 0)
			(effects
				(font
					(size 1.27 1.27)
					(thickness 0.15)
				)
				(justify left bottom)
				(hide yes)
			)
		)
		(property "Manufacturer" "Murata"
			(at 292.1 96.52 0)
			(effects
				(font
					(size 1.27 1.27)
					(thickness 0.15)
				)
				(justify left bottom)
				(hide yes)
			)
		)
		(property "License" "Apache-2.0"
			(at 294.64 96.52 0)
			(effects
				(font
					(size 1.27 1.27)
					(thickness 0.15)
				)
				(justify left bottom)
				(hide yes)
			)
		)
		(property "Author" "Antmicro"
			(at 297.18 96.52 0)
			(effects
				(font
					(size 1.27 1.27)
					(thickness 0.15)
				)
				(justify left bottom)
				(hide yes)
			)
		)
		(property "Val" "22u"
			(at 274.32 115.5636 90)
			(effects
				(font
					(size 1.27 1.27)
					(thickness 0.15)
				)
				(justify right)
			)
		)
		(property "Voltage" ""
			(at 299.72 96.52 0)
			(effects
				(font
					(size 1.27 1.27)
				)
				(justify left bottom)
				(hide yes)
			)
		)
		(property "Dielectric" ""
			(at 302.26 96.52 0)
			(effects
				(font
					(size 1.27 1.27)
				)
				(justify left bottom)
				(hide yes)
			)
		)
		(property "Public" ""
			(at 304.8 96.52 0)
			(effects
				(font
					(size 1.27 1.27)
				)
				(justify left bottom)
				(hide yes)
			)
		)
		(pin "2"
		)
		(pin "1"
		)
		(instances
			(project "polarfire-som"
				(path ""
					(reference "C109")
					(unit 1)
				)
			)
		)
	)
	(symbol
		(lib_id "antmicroResistors0402:R_0R_0402")
		(at 102.87 49.53 180)
		(unit 1)
		(exclude_from_sim no)
		(in_bom yes)
		(on_board yes)
		(dnp no)
		(property "Reference" "R93"
			(at 96.52 48.26 0)
			(effects
				(font
					(size 1.27 1.27)
					(thickness 0.15)
				)
			)
		)
		(property "Value" "R_0R_0402"
			(at 82.55 36.83 0)
			(effects
				(font
					(size 1.27 1.27)
					(thickness 0.15)
				)
				(justify left bottom)
				(hide yes)
			)
		)
		(property "Footprint" "antmicro-footprints:R_0402_1005Metric"
			(at 82.55 34.29 0)
			(effects
				(font
					(size 1.27 1.27)
					(thickness 0.15)
				)
				(justify left bottom)
				(hide yes)
			)
		)
		(property "Datasheet" "https://industrial.panasonic.com/cdbs/www-data/pdf/RDA0000/AOA0000C301.pdf"
			(at 82.55 31.75 0)
			(effects
				(font
					(size 1.27 1.27)
					(thickness 0.15)
				)
				(justify left bottom)
				(hide yes)
			)
		)
		(property "Description" "SMD Chip Resistor, Jumper, 0 ohm, 100 mW, 0402 [1005 Metric], Thick Film, General Purpose"
			(at 102.87 49.53 0)
			(effects
				(font
					(size 1.27 1.27)
				)
				(hide yes)
			)
		)
		(property "MPN" "ERJ2GE0R00X"
			(at 82.55 29.21 0)
			(effects
				(font
					(size 1.27 1.27)
					(thickness 0.15)
				)
				(justify left bottom)
				(hide yes)
			)
		)
		(property "Manufacturer" "Panasonic"
			(at 82.55 26.67 0)
			(effects
				(font
					(size 1.27 1.27)
					(thickness 0.15)
				)
				(justify left bottom)
				(hide yes)
			)
		)
		(property "License" "Apache-2.0"
			(at 82.55 24.13 0)
			(effects
				(font
					(size 1.27 1.27)
					(thickness 0.15)
				)
				(justify left bottom)
				(hide yes)
			)
		)
		(property "Author" "Antmicro"
			(at 82.55 21.59 0)
			(effects
				(font
					(size 1.27 1.27)
					(thickness 0.15)
				)
				(justify left bottom)
				(hide yes)
			)
		)
		(property "Val" "0R"
			(at 104.14 48.26 0)
			(effects
				(font
					(size 1.27 1.27)
					(thickness 0.15)
				)
			)
		)
		(property "Tolerance" "~"
			(at 82.55 39.37 0)
			(effects
				(font
					(size 1.27 1.27)
				)
				(justify left bottom)
				(hide yes)
			)
		)
		(property "Current" "1A"
			(at 82.55 19.05 0)
			(effects
				(font
					(size 1.27 1.27)
					(thickness 0.15)
				)
				(justify left bottom)
				(hide yes)
			)
		)
		(property "DNP" "DNP"
			(at 100.33 49.53 0)
			(effects
				(font
					(size 1.27 1.27)
				)
				(hide yes)
			)
		)
		(property "Public" ""
			(at 82.55 19.05 0)
			(effects
				(font
					(size 1.27 1.27)
				)
				(justify left bottom)
				(hide yes)
			)
		)
		(pin "1"
		)
		(pin "2"
		)
		(instances
			(project "polarfire-som"
				(path ""
					(reference "R93")
					(unit 1)
				)
			)
		)
	)
	(symbol
		(lib_id "antmicroResistors0402:R_0R_0402")
		(at 102.87 64.77 180)
		(unit 1)
		(exclude_from_sim no)
		(in_bom yes)
		(on_board yes)
		(dnp no)
		(property "Reference" "R98"
			(at 96.52 63.5 0)
			(effects
				(font
					(size 1.27 1.27)
					(thickness 0.15)
				)
			)
		)
		(property "Value" "R_0R_0402"
			(at 82.55 52.07 0)
			(effects
				(font
					(size 1.27 1.27)
					(thickness 0.15)
				)
				(justify left bottom)
				(hide yes)
			)
		)
		(property "Footprint" "antmicro-footprints:R_0402_1005Metric"
			(at 82.55 49.53 0)
			(effects
				(font
					(size 1.27 1.27)
					(thickness 0.15)
				)
				(justify left bottom)
				(hide yes)
			)
		)
		(property "Datasheet" "https://industrial.panasonic.com/cdbs/www-data/pdf/RDA0000/AOA0000C301.pdf"
			(at 82.55 46.99 0)
			(effects
				(font
					(size 1.27 1.27)
					(thickness 0.15)
				)
				(justify left bottom)
				(hide yes)
			)
		)
		(property "Description" "SMD Chip Resistor, Jumper, 0 ohm, 100 mW, 0402 [1005 Metric], Thick Film, General Purpose"
			(at 102.87 64.77 0)
			(effects
				(font
					(size 1.27 1.27)
				)
				(hide yes)
			)
		)
		(property "MPN" "ERJ2GE0R00X"
			(at 82.55 44.45 0)
			(effects
				(font
					(size 1.27 1.27)
					(thickness 0.15)
				)
				(justify left bottom)
				(hide yes)
			)
		)
		(property "Manufacturer" "Panasonic"
			(at 82.55 41.91 0)
			(effects
				(font
					(size 1.27 1.27)
					(thickness 0.15)
				)
				(justify left bottom)
				(hide yes)
			)
		)
		(property "License" "Apache-2.0"
			(at 82.55 39.37 0)
			(effects
				(font
					(size 1.27 1.27)
					(thickness 0.15)
				)
				(justify left bottom)
				(hide yes)
			)
		)
		(property "Author" "Antmicro"
			(at 82.55 36.83 0)
			(effects
				(font
					(size 1.27 1.27)
					(thickness 0.15)
				)
				(justify left bottom)
				(hide yes)
			)
		)
		(property "Val" "0R"
			(at 104.14 63.5 0)
			(effects
				(font
					(size 1.27 1.27)
					(thickness 0.15)
				)
			)
		)
		(property "Tolerance" "~"
			(at 82.55 54.61 0)
			(effects
				(font
					(size 1.27 1.27)
				)
				(justify left bottom)
				(hide yes)
			)
		)
		(property "Current" "1A"
			(at 82.55 34.29 0)
			(effects
				(font
					(size 1.27 1.27)
					(thickness 0.15)
				)
				(justify left bottom)
				(hide yes)
			)
		)
		(property "Public" ""
			(at 82.55 34.29 0)
			(effects
				(font
					(size 1.27 1.27)
				)
				(justify left bottom)
				(hide yes)
			)
		)
		(pin "1"
		)
		(pin "2"
		)
		(instances
			(project "polarfire-som"
				(path ""
					(reference "R98")
					(unit 1)
				)
			)
		)
	)
	(symbol
		(lib_id "antmicroResistors0603:R_0R01_0603")
		(at 289.56 110.49 0)
		(unit 1)
		(exclude_from_sim no)
		(in_bom yes)
		(on_board yes)
		(dnp no)
		(fields_autoplaced yes)
		(property "Reference" "R49"
			(at 292.1 104.14 0)
			(effects
				(font
					(size 1.27 1.27)
					(thickness 0.15)
				)
			)
		)
		(property "Value" "R_0R01_0603"
			(at 309.88 123.19 0)
			(effects
				(font
					(size 1.27 1.27)
					(thickness 0.15)
				)
				(justify left bottom)
				(hide yes)
			)
		)
		(property "Footprint" "antmicro-footprints:R_0603_1608Metric"
			(at 309.88 125.73 0)
			(effects
				(font
					(size 1.27 1.27)
					(thickness 0.15)
				)
				(justify left bottom)
				(hide yes)
			)
		)
		(property "Datasheet" "https://www.bourns.com/docs/product-datasheets/cfn-a.pdf"
			(at 309.88 128.27 0)
			(effects
				(font
					(size 1.27 1.27)
					(thickness 0.15)
				)
				(justify left bottom)
				(hide yes)
			)
		)
		(property "Description" "SMD Chip Resistor, 10 mohm, ± 1%, 0.5 W, 0603 [1608 Metric], Metal Foil, Current Sensing"
			(at 289.56 110.49 0)
			(effects
				(font
					(size 1.27 1.27)
				)
				(hide yes)
			)
		)
		(property "MPN" "CFN0603AFZ-R010ELF"
			(at 309.88 130.81 0)
			(effects
				(font
					(size 1.27 1.27)
					(thickness 0.15)
				)
				(justify left bottom)
				(hide yes)
			)
		)
		(property "Manufacturer" "Bourns"
			(at 309.88 133.35 0)
			(effects
				(font
					(size 1.27 1.27)
					(thickness 0.15)
				)
				(justify left bottom)
				(hide yes)
			)
		)
		(property "License" "Apache-2.0"
			(at 309.88 135.89 0)
			(effects
				(font
					(size 1.27 1.27)
					(thickness 0.15)
				)
				(justify left bottom)
				(hide yes)
			)
		)
		(property "Author" "Antmicro"
			(at 309.88 138.43 0)
			(effects
				(font
					(size 1.27 1.27)
					(thickness 0.15)
				)
				(justify left bottom)
				(hide yes)
			)
		)
		(property "Val" "0R01"
			(at 292.1 106.68 0)
			(effects
				(font
					(size 1.27 1.27)
					(thickness 0.15)
				)
			)
		)
		(property "Tolerance" "1%"
			(at 309.88 120.65 0)
			(effects
				(font
					(size 1.27 1.27)
				)
				(justify left bottom)
				(hide yes)
			)
		)
		(property "Public" ""
			(at 309.88 140.97 0)
			(effects
				(font
					(size 1.27 1.27)
				)
				(justify left bottom)
				(hide yes)
			)
		)
		(pin "1"
		)
		(pin "2"
		)
		(instances
			(project "polarfire-som"
				(path ""
					(reference "R49")
					(unit 1)
				)
			)
		)
	)
	(symbol
		(lib_id "antmicropower:GND")
		(at 20.32 237.49 0)
		(unit 1)
		(exclude_from_sim no)
		(in_bom yes)
		(on_board yes)
		(dnp no)
		(property "Reference" "#PWR061"
			(at 29.21 240.03 0)
			(effects
				(font
					(size 1.27 1.27)
					(thickness 0.15)
				)
				(justify left bottom)
				(hide yes)
			)
		)
		(property "Value" "GND"
			(at 20.32 241.3 0)
			(effects
				(font
					(size 1.27 1.27)
					(thickness 0.15)
				)
			)
		)
		(property "Footprint" ""
			(at 29.21 245.11 0)
			(effects
				(font
					(size 1.27 1.27)
					(thickness 0.15)
				)
				(justify left bottom)
				(hide yes)
			)
		)
		(property "Datasheet" ""
			(at 29.21 250.19 0)
			(effects
				(font
					(size 1.27 1.27)
					(thickness 0.15)
				)
				(justify left bottom)
				(hide yes)
			)
		)
		(property "Description" ""
			(at 20.32 237.49 0)
			(effects
				(font
					(size 1.27 1.27)
				)
				(hide yes)
			)
		)
		(property "Author" "Antmicro"
			(at 29.21 245.11 0)
			(effects
				(font
					(size 1.27 1.27)
					(thickness 0.15)
				)
				(justify left bottom)
				(hide yes)
			)
		)
		(property "License" "Apache-2.0"
			(at 29.21 247.65 0)
			(effects
				(font
					(size 1.27 1.27)
					(thickness 0.15)
				)
				(justify left bottom)
				(hide yes)
			)
		)
		(pin "1"
		)
		(instances
			(project "polarfire-som"
				(path ""
					(reference "#PWR061")
					(unit 1)
				)
			)
		)
	)
	(symbol
		(lib_id "antmicropower:+2V5")
		(at 299.72 74.93 0)
		(unit 1)
		(exclude_from_sim no)
		(in_bom yes)
		(on_board yes)
		(dnp no)
		(fields_autoplaced yes)
		(property "Reference" "#PWR0182"
			(at 299.72 78.74 0)
			(effects
				(font
					(size 1.27 1.27)
				)
				(hide yes)
			)
		)
		(property "Value" "+2V5"
			(at 299.72 70.485 0)
			(effects
				(font
					(size 1.27 1.27)
				)
			)
		)
		(property "Footprint" ""
			(at 299.72 74.93 0)
			(effects
				(font
					(size 1.27 1.27)
				)
				(hide yes)
			)
		)
		(property "Datasheet" ""
			(at 299.72 74.93 0)
			(effects
				(font
					(size 1.27 1.27)
				)
				(hide yes)
			)
		)
		(property "Description" ""
			(at 299.72 74.93 0)
			(effects
				(font
					(size 1.27 1.27)
				)
				(hide yes)
			)
		)
		(pin "1"
		)
		(instances
			(project "polarfire-som"
				(path ""
					(reference "#PWR0182")
					(unit 1)
				)
			)
		)
	)
	(symbol
		(lib_id "antmicropower:+3V3")
		(at 62.23 209.55 0)
		(unit 1)
		(exclude_from_sim no)
		(in_bom yes)
		(on_board yes)
		(dnp no)
		(property "Reference" "#PWR070"
			(at 77.47 212.09 0)
			(effects
				(font
					(size 1.27 1.27)
					(thickness 0.15)
				)
				(justify left bottom)
				(hide yes)
			)
		)
		(property "Value" "+3V3"
			(at 62.23 205.74 0)
			(effects
				(font
					(size 1.27 1.27)
					(thickness 0.15)
				)
			)
		)
		(property "Footprint" ""
			(at 77.47 217.17 0)
			(effects
				(font
					(size 1.27 1.27)
					(thickness 0.15)
				)
				(justify left bottom)
				(hide yes)
			)
		)
		(property "Datasheet" ""
			(at 77.47 219.71 0)
			(effects
				(font
					(size 1.27 1.27)
					(thickness 0.15)
				)
				(justify left bottom)
				(hide yes)
			)
		)
		(property "Description" ""
			(at 62.23 209.55 0)
			(effects
				(font
					(size 1.27 1.27)
				)
				(hide yes)
			)
		)
		(property "Author" "Antmicro"
			(at 77.47 217.17 0)
			(effects
				(font
					(size 1.27 1.27)
					(thickness 0.15)
				)
				(justify left bottom)
				(hide yes)
			)
		)
		(property "License" "Apache-2.0"
			(at 77.47 219.71 0)
			(effects
				(font
					(size 1.27 1.27)
					(thickness 0.15)
				)
				(justify left bottom)
				(hide yes)
			)
		)
		(pin "1"
		)
		(instances
			(project "polarfire-som"
				(path ""
					(reference "#PWR070")
					(unit 1)
				)
			)
		)
	)
	(symbol
		(lib_id "antmicropower:GND")
		(at 191.77 76.2 0)
		(unit 1)
		(exclude_from_sim no)
		(in_bom yes)
		(on_board yes)
		(dnp no)
		(fields_autoplaced yes)
		(property "Reference" "#PWR091"
			(at 200.66 78.74 0)
			(effects
				(font
					(size 1.27 1.27)
					(thickness 0.15)
				)
				(justify left bottom)
				(hide yes)
			)
		)
		(property "Value" "GND"
			(at 191.77 81.28 0)
			(effects
				(font
					(size 1.27 1.27)
					(thickness 0.15)
				)
			)
		)
		(property "Footprint" ""
			(at 200.66 83.82 0)
			(effects
				(font
					(size 1.27 1.27)
					(thickness 0.15)
				)
				(justify left bottom)
				(hide yes)
			)
		)
		(property "Datasheet" ""
			(at 200.66 88.9 0)
			(effects
				(font
					(size 1.27 1.27)
					(thickness 0.15)
				)
				(justify left bottom)
				(hide yes)
			)
		)
		(property "Description" ""
			(at 191.77 76.2 0)
			(effects
				(font
					(size 1.27 1.27)
				)
				(hide yes)
			)
		)
		(property "Author" "Antmicro"
			(at 200.66 83.82 0)
			(effects
				(font
					(size 1.27 1.27)
					(thickness 0.15)
				)
				(justify left bottom)
				(hide yes)
			)
		)
		(property "License" "Apache-2.0"
			(at 200.66 86.36 0)
			(effects
				(font
					(size 1.27 1.27)
					(thickness 0.15)
				)
				(justify left bottom)
				(hide yes)
			)
		)
		(pin "1"
		)
		(instances
			(project "polarfire-som"
				(path ""
					(reference "#PWR091")
					(unit 1)
				)
			)
		)
	)
	(symbol
		(lib_id "antmicropower:VDDI")
		(at 88.9 196.85 0)
		(unit 1)
		(exclude_from_sim no)
		(in_bom yes)
		(on_board yes)
		(dnp no)
		(fields_autoplaced yes)
		(property "Reference" "#PWR0322"
			(at 88.9 200.66 0)
			(effects
				(font
					(size 1.27 1.27)
				)
				(hide yes)
			)
		)
		(property "Value" "VDD"
			(at 88.9 192.405 0)
			(effects
				(font
					(size 1.27 1.27)
				)
			)
		)
		(property "Footprint" ""
			(at 88.9 196.85 0)
			(effects
				(font
					(size 1.27 1.27)
				)
				(hide yes)
			)
		)
		(property "Datasheet" ""
			(at 88.9 196.85 0)
			(effects
				(font
					(size 1.27 1.27)
				)
				(hide yes)
			)
		)
		(property "Description" ""
			(at 88.9 196.85 0)
			(effects
				(font
					(size 1.27 1.27)
				)
				(hide yes)
			)
		)
		(pin "1"
		)
		(instances
			(project "polarfire-som"
				(path ""
					(reference "#PWR0322")
					(unit 1)
				)
			)
		)
	)
	(symbol
		(lib_id "antmicroCapacitors0402:C_10u_10V_0402")
		(at 200.66 74.93 90)
		(unit 1)
		(exclude_from_sim no)
		(in_bom yes)
		(on_board yes)
		(dnp no)
		(fields_autoplaced yes)
		(property "Reference" "C93"
			(at 203.2 71.1136 90)
			(effects
				(font
					(size 1.27 1.27)
					(thickness 0.15)
				)
				(justify right)
			)
		)
		(property "Value" "C_10u_10V_0402"
			(at 210.82 54.61 0)
			(effects
				(font
					(size 1.27 1.27)
					(thickness 0.15)
				)
				(justify left bottom)
				(hide yes)
			)
		)
		(property "Footprint" "antmicro-footprints:C_0402_1005Metric"
			(at 213.36 54.61 0)
			(effects
				(font
					(size 1.27 1.27)
					(thickness 0.15)
				)
				(justify left bottom)
				(hide yes)
			)
		)
		(property "Datasheet" "https://www.murata.com/products/productdetail?partno=GRM155R61A106ME11%23"
			(at 215.9 54.61 0)
			(effects
				(font
					(size 1.27 1.27)
					(thickness 0.15)
				)
				(justify left bottom)
				(hide yes)
			)
		)
		(property "Description" "Multilayer Ceramic Capacitors MLCC - SMD/SMT 10 uF 10 VDC 20% 0402 X5R"
			(at 200.66 74.93 0)
			(effects
				(font
					(size 1.27 1.27)
				)
				(hide yes)
			)
		)
		(property "MPN" "GRM155R61A106ME11D"
			(at 218.44 54.61 0)
			(effects
				(font
					(size 1.27 1.27)
					(thickness 0.15)
				)
				(justify left bottom)
				(hide yes)
			)
		)
		(property "Manufacturer" "Murata"
			(at 220.98 54.61 0)
			(effects
				(font
					(size 1.27 1.27)
					(thickness 0.15)
				)
				(justify left bottom)
				(hide yes)
			)
		)
		(property "License" "Apache-2.0"
			(at 223.52 54.61 0)
			(effects
				(font
					(size 1.27 1.27)
					(thickness 0.15)
				)
				(justify left bottom)
				(hide yes)
			)
		)
		(property "Author" "Antmicro"
			(at 226.06 54.61 0)
			(effects
				(font
					(size 1.27 1.27)
					(thickness 0.15)
				)
				(justify left bottom)
				(hide yes)
			)
		)
		(property "Val" "10u"
			(at 203.2 73.6536 90)
			(effects
				(font
					(size 1.27 1.27)
					(thickness 0.15)
				)
				(justify right)
			)
		)
		(property "Voltage" "10V"
			(at 228.6 54.61 0)
			(effects
				(font
					(size 1.27 1.27)
				)
				(justify left bottom)
				(hide yes)
			)
		)
		(property "Dielectric" "X5R"
			(at 231.14 54.61 0)
			(effects
				(font
					(size 1.27 1.27)
				)
				(justify left bottom)
				(hide yes)
			)
		)
		(property "Public" ""
			(at 233.68 54.61 0)
			(effects
				(font
					(size 1.27 1.27)
				)
				(justify left bottom)
				(hide yes)
			)
		)
		(pin "1"
		)
		(pin "2"
		)
		(instances
			(project "polarfire-som"
				(path ""
					(reference "C93")
					(unit 1)
				)
			)
		)
	)
	(symbol
		(lib_id "antmicropower:+1V2")
		(at 299.72 109.22 0)
		(unit 1)
		(exclude_from_sim no)
		(in_bom yes)
		(on_board yes)
		(dnp no)
		(fields_autoplaced yes)
		(property "Reference" "#PWR0184"
			(at 299.72 113.03 0)
			(effects
				(font
					(size 1.27 1.27)
				)
				(hide yes)
			)
		)
		(property "Value" "+1V2"
			(at 299.72 104.14 0)
			(effects
				(font
					(size 1.27 1.27)
				)
			)
		)
		(property "Footprint" ""
			(at 299.72 109.22 0)
			(effects
				(font
					(size 1.27 1.27)
				)
				(hide yes)
			)
		)
		(property "Datasheet" ""
			(at 299.72 109.22 0)
			(effects
				(font
					(size 1.27 1.27)
				)
				(hide yes)
			)
		)
		(property "Description" ""
			(at 299.72 109.22 0)
			(effects
				(font
					(size 1.27 1.27)
				)
				(hide yes)
			)
		)
		(pin "1"
		)
		(instances
			(project "polarfire-som"
				(path ""
					(reference "#PWR0184")
					(unit 1)
				)
			)
		)
	)
	(symbol
		(lib_id "antmicropower:GND")
		(at 24.13 60.96 0)
		(unit 1)
		(exclude_from_sim no)
		(in_bom yes)
		(on_board yes)
		(dnp no)
		(property "Reference" "#PWR063"
			(at 33.02 63.5 0)
			(effects
				(font
					(size 1.27 1.27)
					(thickness 0.15)
				)
				(justify left bottom)
				(hide yes)
			)
		)
		(property "Value" "GND"
			(at 24.13 64.77 0)
			(effects
				(font
					(size 1.27 1.27)
					(thickness 0.15)
				)
			)
		)
		(property "Footprint" ""
			(at 33.02 68.58 0)
			(effects
				(font
					(size 1.27 1.27)
					(thickness 0.15)
				)
				(justify left bottom)
				(hide yes)
			)
		)
		(property "Datasheet" ""
			(at 33.02 73.66 0)
			(effects
				(font
					(size 1.27 1.27)
					(thickness 0.15)
				)
				(justify left bottom)
				(hide yes)
			)
		)
		(property "Description" ""
			(at 24.13 60.96 0)
			(effects
				(font
					(size 1.27 1.27)
				)
				(hide yes)
			)
		)
		(property "Author" "Antmicro"
			(at 33.02 68.58 0)
			(effects
				(font
					(size 1.27 1.27)
					(thickness 0.15)
				)
				(justify left bottom)
				(hide yes)
			)
		)
		(property "License" "Apache-2.0"
			(at 33.02 71.12 0)
			(effects
				(font
					(size 1.27 1.27)
					(thickness 0.15)
				)
				(justify left bottom)
				(hide yes)
			)
		)
		(pin "1"
		)
		(instances
			(project "polarfire-som"
				(path ""
					(reference "#PWR063")
					(unit 1)
				)
			)
		)
	)
	(symbol
		(lib_id "antmicropower:GND")
		(at 165.1 76.2 0)
		(unit 1)
		(exclude_from_sim no)
		(in_bom yes)
		(on_board yes)
		(dnp no)
		(fields_autoplaced yes)
		(property "Reference" "#PWR085"
			(at 173.99 78.74 0)
			(effects
				(font
					(size 1.27 1.27)
					(thickness 0.15)
				)
				(justify left bottom)
				(hide yes)
			)
		)
		(property "Value" "GND"
			(at 165.1 81.28 0)
			(effects
				(font
					(size 1.27 1.27)
					(thickness 0.15)
				)
			)
		)
		(property "Footprint" ""
			(at 173.99 83.82 0)
			(effects
				(font
					(size 1.27 1.27)
					(thickness 0.15)
				)
				(justify left bottom)
				(hide yes)
			)
		)
		(property "Datasheet" ""
			(at 173.99 88.9 0)
			(effects
				(font
					(size 1.27 1.27)
					(thickness 0.15)
				)
				(justify left bottom)
				(hide yes)
			)
		)
		(property "Description" ""
			(at 165.1 76.2 0)
			(effects
				(font
					(size 1.27 1.27)
				)
				(hide yes)
			)
		)
		(property "Author" "Antmicro"
			(at 173.99 83.82 0)
			(effects
				(font
					(size 1.27 1.27)
					(thickness 0.15)
				)
				(justify left bottom)
				(hide yes)
			)
		)
		(property "License" "Apache-2.0"
			(at 173.99 86.36 0)
			(effects
				(font
					(size 1.27 1.27)
					(thickness 0.15)
				)
				(justify left bottom)
				(hide yes)
			)
		)
		(pin "1"
		)
		(instances
			(project "polarfire-som"
				(path ""
					(reference "#PWR085")
					(unit 1)
				)
			)
		)
	)
	(symbol
		(lib_id "antmicropower:GND")
		(at 252.73 250.19 0)
		(unit 1)
		(exclude_from_sim no)
		(in_bom yes)
		(on_board yes)
		(dnp no)
		(fields_autoplaced yes)
		(property "Reference" "#PWR097"
			(at 252.73 256.54 0)
			(effects
				(font
					(size 1.27 1.27)
				)
				(hide yes)
			)
		)
		(property "Value" "GND"
			(at 252.73 255.27 0)
			(effects
				(font
					(size 1.27 1.27)
					(thickness 0.15)
				)
			)
		)
		(property "Footprint" ""
			(at 261.62 257.81 0)
			(effects
				(font
					(size 1.27 1.27)
					(thickness 0.15)
				)
				(justify left bottom)
				(hide yes)
			)
		)
		(property "Datasheet" ""
			(at 261.62 262.89 0)
			(effects
				(font
					(size 1.27 1.27)
					(thickness 0.15)
				)
				(justify left bottom)
				(hide yes)
			)
		)
		(property "Description" ""
			(at 252.73 250.19 0)
			(effects
				(font
					(size 1.27 1.27)
				)
				(hide yes)
			)
		)
		(property "Author" "Antmicro"
			(at 261.62 257.81 0)
			(effects
				(font
					(size 1.27 1.27)
					(thickness 0.15)
				)
				(justify left bottom)
				(hide yes)
			)
		)
		(property "License" "Apache-2.0"
			(at 261.62 260.35 0)
			(effects
				(font
					(size 1.27 1.27)
					(thickness 0.15)
				)
				(justify left bottom)
				(hide yes)
			)
		)
		(pin "1"
		)
		(instances
			(project "polarfire-som"
				(path ""
					(reference "#PWR097")
					(unit 1)
				)
			)
		)
	)
	(symbol
		(lib_id "antmicropower:+5V")
		(at 172.72 148.59 0)
		(unit 1)
		(exclude_from_sim no)
		(in_bom yes)
		(on_board yes)
		(dnp no)
		(fields_autoplaced yes)
		(property "Reference" "#PWR362"
			(at 187.96 151.13 0)
			(effects
				(font
					(size 1.27 1.27)
					(thickness 0.15)
				)
				(justify left bottom)
				(hide yes)
			)
		)
		(property "Value" "+5V"
			(at 172.72 143.51 0)
			(effects
				(font
					(size 1.27 1.27)
					(thickness 0.15)
				)
			)
		)
		(property "Footprint" ""
			(at 187.96 156.21 0)
			(effects
				(font
					(size 1.27 1.27)
					(thickness 0.15)
				)
				(justify left bottom)
				(hide yes)
			)
		)
		(property "Datasheet" ""
			(at 187.96 158.75 0)
			(effects
				(font
					(size 1.27 1.27)
					(thickness 0.15)
				)
				(justify left bottom)
				(hide yes)
			)
		)
		(property "Description" ""
			(at 172.72 148.59 0)
			(effects
				(font
					(size 1.27 1.27)
				)
				(hide yes)
			)
		)
		(property "Author" "Antmicro"
			(at 187.96 156.21 0)
			(effects
				(font
					(size 1.27 1.27)
					(thickness 0.15)
				)
				(justify left bottom)
				(hide yes)
			)
		)
		(property "License" "Apache-2.0"
			(at 187.96 158.75 0)
			(effects
				(font
					(size 1.27 1.27)
					(thickness 0.15)
				)
				(justify left bottom)
				(hide yes)
			)
		)
		(pin "1"
		)
		(instances
			(project "polarfire-som"
				(path ""
					(reference "#PWR362")
					(unit 1)
				)
			)
		)
	)
	(symbol
		(lib_id "antmicroResistors0402:R_205k_0402")
		(at 290.83 247.65 90)
		(unit 1)
		(exclude_from_sim no)
		(in_bom yes)
		(on_board yes)
		(dnp no)
		(fields_autoplaced yes)
		(property "Reference" "R19"
			(at 293.37 243.84 90)
			(effects
				(font
					(size 1.27 1.27)
					(thickness 0.15)
				)
				(justify right)
			)
		)
		(property "Value" "R_205k_0402"
			(at 303.53 227.33 0)
			(effects
				(font
					(size 1.27 1.27)
					(thickness 0.15)
				)
				(justify left bottom)
				(hide yes)
			)
		)
		(property "Footprint" "antmicro-footprints:R_0402_1005Metric"
			(at 306.07 227.33 0)
			(effects
				(font
					(size 1.27 1.27)
					(thickness 0.15)
				)
				(justify left bottom)
				(hide yes)
			)
		)
		(property "Datasheet" "https://www.bourns.com/docs/product-datasheets/cr.pdf"
			(at 308.61 227.33 0)
			(effects
				(font
					(size 1.27 1.27)
					(thickness 0.15)
				)
				(justify left bottom)
				(hide yes)
			)
		)
		(property "Description" "SMD Chip Resistor"
			(at 290.83 247.65 0)
			(effects
				(font
					(size 1.27 1.27)
				)
				(hide yes)
			)
		)
		(property "MPN" "CR0402-FX-2053GLF"
			(at 311.15 227.33 0)
			(effects
				(font
					(size 1.27 1.27)
					(thickness 0.15)
				)
				(justify left bottom)
				(hide yes)
			)
		)
		(property "Manufacturer" "Bourns"
			(at 313.69 227.33 0)
			(effects
				(font
					(size 1.27 1.27)
					(thickness 0.15)
				)
				(justify left bottom)
				(hide yes)
			)
		)
		(property "License" "Apache-2.0"
			(at 316.23 227.33 0)
			(effects
				(font
					(size 1.27 1.27)
					(thickness 0.15)
				)
				(justify left bottom)
				(hide yes)
			)
		)
		(property "Author" "Antmicro"
			(at 318.77 227.33 0)
			(effects
				(font
					(size 1.27 1.27)
					(thickness 0.15)
				)
				(justify left bottom)
				(hide yes)
			)
		)
		(property "Val" "205k"
			(at 293.37 246.38 90)
			(effects
				(font
					(size 1.27 1.27)
					(thickness 0.15)
				)
				(justify right)
			)
		)
		(property "Tolerance" "1%"
			(at 300.99 227.33 0)
			(effects
				(font
					(size 1.27 1.27)
				)
				(justify left bottom)
				(hide yes)
			)
		)
		(property "Public" ""
			(at 321.31 227.33 0)
			(effects
				(font
					(size 1.27 1.27)
				)
				(justify left bottom)
				(hide yes)
			)
		)
		(pin "2"
		)
		(pin "1"
		)
		(instances
			(project "polarfire-som"
				(path ""
					(reference "R19")
					(unit 1)
				)
			)
		)
	)
	(symbol
		(lib_id "antmicroCapacitors0402:C_22u_0402")
		(at 165.1 74.93 90)
		(unit 1)
		(exclude_from_sim no)
		(in_bom yes)
		(on_board yes)
		(dnp no)
		(fields_autoplaced yes)
		(property "Reference" "C85"
			(at 167.64 71.1136 90)
			(effects
				(font
					(size 1.27 1.27)
					(thickness 0.15)
				)
				(justify right)
			)
		)
		(property "Value" "C_22u_0402"
			(at 175.26 54.61 0)
			(effects
				(font
					(size 1.27 1.27)
					(thickness 0.15)
				)
				(justify left bottom)
				(hide yes)
			)
		)
		(property "Footprint" "antmicro-footprints:C_0402_1005Metric"
			(at 177.8 54.61 0)
			(effects
				(font
					(size 1.27 1.27)
					(thickness 0.15)
				)
				(justify left bottom)
				(hide yes)
			)
		)
		(property "Datasheet" "https://www.murata.com/products/productdetail?partno=GRM158R60J226ME01%23"
			(at 180.34 54.61 0)
			(effects
				(font
					(size 1.27 1.27)
					(thickness 0.15)
				)
				(justify left bottom)
				(hide yes)
			)
		)
		(property "Description" "SMD Multilayer Ceramic Capacitor, 22 uF, 4 V, 0402 [1005 Metric], X6S"
			(at 165.1 74.93 0)
			(effects
				(font
					(size 1.27 1.27)
				)
				(hide yes)
			)
		)
		(property "MPN" "GRM158R60J226ME01D"
			(at 182.88 54.61 0)
			(effects
				(font
					(size 1.27 1.27)
					(thickness 0.15)
				)
				(justify left bottom)
				(hide yes)
			)
		)
		(property "Manufacturer" "Murata"
			(at 185.42 54.61 0)
			(effects
				(font
					(size 1.27 1.27)
					(thickness 0.15)
				)
				(justify left bottom)
				(hide yes)
			)
		)
		(property "License" "Apache-2.0"
			(at 187.96 54.61 0)
			(effects
				(font
					(size 1.27 1.27)
					(thickness 0.15)
				)
				(justify left bottom)
				(hide yes)
			)
		)
		(property "Author" "Antmicro"
			(at 190.5 54.61 0)
			(effects
				(font
					(size 1.27 1.27)
					(thickness 0.15)
				)
				(justify left bottom)
				(hide yes)
			)
		)
		(property "Val" "22u"
			(at 167.64 73.6536 90)
			(effects
				(font
					(size 1.27 1.27)
					(thickness 0.15)
				)
				(justify right)
			)
		)
		(property "Voltage" ""
			(at 193.04 54.61 0)
			(effects
				(font
					(size 1.27 1.27)
				)
				(justify left bottom)
				(hide yes)
			)
		)
		(property "Dielectric" ""
			(at 195.58 54.61 0)
			(effects
				(font
					(size 1.27 1.27)
				)
				(justify left bottom)
				(hide yes)
			)
		)
		(property "Public" ""
			(at 198.12 54.61 0)
			(effects
				(font
					(size 1.27 1.27)
				)
				(justify left bottom)
				(hide yes)
			)
		)
		(pin "2"
		)
		(pin "1"
		)
		(instances
			(project "polarfire-som"
				(path ""
					(reference "C85")
					(unit 1)
				)
			)
		)
	)
	(symbol
		(lib_id "antmicroResistors0603:R_0R_22.4A_0603")
		(at 289.56 76.2 0)
		(unit 1)
		(exclude_from_sim no)
		(in_bom yes)
		(on_board yes)
		(dnp no)
		(property "Reference" "R53"
			(at 292.1 71.12 0)
			(effects
				(font
					(size 1.27 1.27)
					(thickness 0.15)
				)
			)
		)
		(property "Value" "R_0R_22.4A_0603"
			(at 292.1 67.31 0)
			(effects
				(font
					(size 1.27 1.27)
					(thickness 0.15)
				)
				(hide yes)
			)
		)
		(property "Footprint" "antmicro-footprints:R_0603_1608Metric"
			(at 304.8 86.36 0)
			(effects
				(font
					(size 1.27 1.27)
					(thickness 0.15)
				)
				(justify left bottom)
				(hide yes)
			)
		)
		(property "Datasheet" "https://fscdn.rohm.com/en/products/databook/datasheet/passive/resistor/chip_resistor/pmr-jpw-e.pdf"
			(at 304.8 88.9 0)
			(effects
				(font
					(size 1.27 1.27)
					(thickness 0.15)
				)
				(justify left bottom)
				(hide yes)
			)
		)
		(property "Description" "SMD Chip Resistor"
			(at 289.56 76.2 0)
			(effects
				(font
					(size 1.27 1.27)
				)
				(hide yes)
			)
		)
		(property "MPN" "PMR03EZPJ000"
			(at 304.8 91.44 0)
			(effects
				(font
					(size 1.27 1.27)
					(thickness 0.15)
				)
				(justify left bottom)
				(hide yes)
			)
		)
		(property "Manufacturer" "ROHM Semiconductor"
			(at 304.8 93.98 0)
			(effects
				(font
					(size 1.27 1.27)
					(thickness 0.15)
				)
				(justify left bottom)
				(hide yes)
			)
		)
		(property "Val" "0R"
			(at 292.1 73.66 0)
			(effects
				(font
					(size 1.27 1.27)
					(thickness 0.15)
				)
			)
		)
		(property "Max. Curr." "22.4A"
			(at 297.18 78.74 0)
			(effects
				(font
					(size 1.27 1.27)
					(thickness 0.15)
				)
				(hide yes)
			)
		)
		(property "Author" "Antmicro"
			(at 304.8 99.06 0)
			(effects
				(font
					(size 1.27 1.27)
					(thickness 0.15)
				)
				(justify left bottom)
				(hide yes)
			)
		)
		(property "License" "Apache-2.0"
			(at 304.8 101.6 0)
			(effects
				(font
					(size 1.27 1.27)
					(thickness 0.15)
				)
				(justify left bottom)
				(hide yes)
			)
		)
		(property "Tolerance" "template_tolerance"
			(at 309.88 86.36 0)
			(effects
				(font
					(size 1.27 1.27)
				)
				(justify left bottom)
				(hide yes)
			)
		)
		(property "Public" ""
			(at 309.88 106.68 0)
			(effects
				(font
					(size 1.27 1.27)
				)
				(justify left bottom)
				(hide yes)
			)
		)
		(pin "1"
		)
		(pin "2"
		)
		(instances
			(project "polarfire-som"
				(path ""
					(reference "R53")
					(unit 1)
				)
			)
		)
	)
	(symbol
		(lib_id "antmicroCapacitors0402:C_22u_0402")
		(at 189.23 215.9 90)
		(unit 1)
		(exclude_from_sim no)
		(in_bom yes)
		(on_board yes)
		(dnp no)
		(fields_autoplaced yes)
		(property "Reference" "C88"
			(at 191.77 212.0836 90)
			(effects
				(font
					(size 1.27 1.27)
					(thickness 0.15)
				)
				(justify right)
			)
		)
		(property "Value" "C_22u_0402"
			(at 199.39 195.58 0)
			(effects
				(font
					(size 1.27 1.27)
					(thickness 0.15)
				)
				(justify left bottom)
				(hide yes)
			)
		)
		(property "Footprint" "antmicro-footprints:C_0402_1005Metric"
			(at 201.93 195.58 0)
			(effects
				(font
					(size 1.27 1.27)
					(thickness 0.15)
				)
				(justify left bottom)
				(hide yes)
			)
		)
		(property "Datasheet" "https://www.murata.com/products/productdetail?partno=GRM158R60J226ME01%23"
			(at 204.47 195.58 0)
			(effects
				(font
					(size 1.27 1.27)
					(thickness 0.15)
				)
				(justify left bottom)
				(hide yes)
			)
		)
		(property "Description" "SMD Multilayer Ceramic Capacitor, 22 uF, 4 V, 0402 [1005 Metric], X6S"
			(at 189.23 215.9 0)
			(effects
				(font
					(size 1.27 1.27)
				)
				(hide yes)
			)
		)
		(property "MPN" "GRM158R60J226ME01D"
			(at 207.01 195.58 0)
			(effects
				(font
					(size 1.27 1.27)
					(thickness 0.15)
				)
				(justify left bottom)
				(hide yes)
			)
		)
		(property "Manufacturer" "Murata"
			(at 209.55 195.58 0)
			(effects
				(font
					(size 1.27 1.27)
					(thickness 0.15)
				)
				(justify left bottom)
				(hide yes)
			)
		)
		(property "License" "Apache-2.0"
			(at 212.09 195.58 0)
			(effects
				(font
					(size 1.27 1.27)
					(thickness 0.15)
				)
				(justify left bottom)
				(hide yes)
			)
		)
		(property "Author" "Antmicro"
			(at 214.63 195.58 0)
			(effects
				(font
					(size 1.27 1.27)
					(thickness 0.15)
				)
				(justify left bottom)
				(hide yes)
			)
		)
		(property "Val" "22u"
			(at 191.77 214.6236 90)
			(effects
				(font
					(size 1.27 1.27)
					(thickness 0.15)
				)
				(justify right)
			)
		)
		(property "Voltage" ""
			(at 217.17 195.58 0)
			(effects
				(font
					(size 1.27 1.27)
				)
				(justify left bottom)
				(hide yes)
			)
		)
		(property "Dielectric" ""
			(at 219.71 195.58 0)
			(effects
				(font
					(size 1.27 1.27)
				)
				(justify left bottom)
				(hide yes)
			)
		)
		(property "Public" ""
			(at 222.25 195.58 0)
			(effects
				(font
					(size 1.27 1.27)
				)
				(justify left bottom)
				(hide yes)
			)
		)
		(pin "2"
		)
		(pin "1"
		)
		(instances
			(project "polarfire-som"
				(path ""
					(reference "C88")
					(unit 1)
				)
			)
		)
	)
	(symbol
		(lib_id "antmicropower:+3V3")
		(at 62.23 242.57 0)
		(unit 1)
		(exclude_from_sim no)
		(in_bom yes)
		(on_board yes)
		(dnp no)
		(property "Reference" "#PWR071"
			(at 77.47 245.11 0)
			(effects
				(font
					(size 1.27 1.27)
					(thickness 0.15)
				)
				(justify left bottom)
				(hide yes)
			)
		)
		(property "Value" "+3V3"
			(at 62.23 238.76 0)
			(effects
				(font
					(size 1.27 1.27)
					(thickness 0.15)
				)
			)
		)
		(property "Footprint" ""
			(at 77.47 250.19 0)
			(effects
				(font
					(size 1.27 1.27)
					(thickness 0.15)
				)
				(justify left bottom)
				(hide yes)
			)
		)
		(property "Datasheet" ""
			(at 77.47 252.73 0)
			(effects
				(font
					(size 1.27 1.27)
					(thickness 0.15)
				)
				(justify left bottom)
				(hide yes)
			)
		)
		(property "Description" ""
			(at 62.23 242.57 0)
			(effects
				(font
					(size 1.27 1.27)
				)
				(hide yes)
			)
		)
		(property "Author" "Antmicro"
			(at 77.47 250.19 0)
			(effects
				(font
					(size 1.27 1.27)
					(thickness 0.15)
				)
				(justify left bottom)
				(hide yes)
			)
		)
		(property "License" "Apache-2.0"
			(at 77.47 252.73 0)
			(effects
				(font
					(size 1.27 1.27)
					(thickness 0.15)
				)
				(justify left bottom)
				(hide yes)
			)
		)
		(pin "1"
		)
		(instances
			(project "polarfire-som"
				(path ""
					(reference "#PWR071")
					(unit 1)
				)
			)
		)
	)
	(symbol
		(lib_id "antmicroCapacitors0402:C_22u_0402")
		(at 265.43 227.33 90)
		(unit 1)
		(exclude_from_sim no)
		(in_bom yes)
		(on_board yes)
		(dnp no)
		(property "Reference" "C98"
			(at 266.065 222.885 90)
			(effects
				(font
					(size 1.27 1.27)
					(thickness 0.15)
				)
				(justify right)
			)
		)
		(property "Value" "C_22u_0402"
			(at 275.59 207.01 0)
			(effects
				(font
					(size 1.27 1.27)
					(thickness 0.15)
				)
				(justify left bottom)
				(hide yes)
			)
		)
		(property "Footprint" "antmicro-footprints:C_0402_1005Metric"
			(at 278.13 207.01 0)
			(effects
				(font
					(size 1.27 1.27)
					(thickness 0.15)
				)
				(justify left bottom)
				(hide yes)
			)
		)
		(property "Datasheet" "https://www.murata.com/products/productdetail?partno=GRM158R60J226ME01%23"
			(at 280.67 207.01 0)
			(effects
				(font
					(size 1.27 1.27)
					(thickness 0.15)
				)
				(justify left bottom)
				(hide yes)
			)
		)
		(property "Description" "SMD Multilayer Ceramic Capacitor, 22 uF, 4 V, 0402 [1005 Metric], X6S"
			(at 265.43 227.33 0)
			(effects
				(font
					(size 1.27 1.27)
				)
				(hide yes)
			)
		)
		(property "MPN" "GRM158R60J226ME01D"
			(at 283.21 207.01 0)
			(effects
				(font
					(size 1.27 1.27)
					(thickness 0.15)
				)
				(justify left bottom)
				(hide yes)
			)
		)
		(property "Manufacturer" "Murata"
			(at 285.75 207.01 0)
			(effects
				(font
					(size 1.27 1.27)
					(thickness 0.15)
				)
				(justify left bottom)
				(hide yes)
			)
		)
		(property "License" "Apache-2.0"
			(at 288.29 207.01 0)
			(effects
				(font
					(size 1.27 1.27)
					(thickness 0.15)
				)
				(justify left bottom)
				(hide yes)
			)
		)
		(property "Author" "Antmicro"
			(at 290.83 207.01 0)
			(effects
				(font
					(size 1.27 1.27)
					(thickness 0.15)
				)
				(justify left bottom)
				(hide yes)
			)
		)
		(property "Val" "22u"
			(at 266.065 226.695 90)
			(effects
				(font
					(size 1.27 1.27)
					(thickness 0.15)
				)
				(justify right)
			)
		)
		(property "Voltage" ""
			(at 293.37 207.01 0)
			(effects
				(font
					(size 1.27 1.27)
				)
				(justify left bottom)
				(hide yes)
			)
		)
		(property "Dielectric" ""
			(at 295.91 207.01 0)
			(effects
				(font
					(size 1.27 1.27)
				)
				(justify left bottom)
				(hide yes)
			)
		)
		(property "Public" ""
			(at 298.45 207.01 0)
			(effects
				(font
					(size 1.27 1.27)
				)
				(justify left bottom)
				(hide yes)
			)
		)
		(pin "2"
		)
		(pin "1"
		)
		(instances
			(project "polarfire-som"
				(path ""
					(reference "C98")
					(unit 1)
				)
			)
		)
	)
	(symbol
		(lib_id "antmicroTestPoints:TP_0.75mm_SMD")
		(at 158.75 132.08 180)
		(unit 1)
		(exclude_from_sim no)
		(in_bom no)
		(on_board yes)
		(dnp no)
		(property "Reference" "TP25"
			(at 151.765 132.08 0)
			(effects
				(font
					(size 1.27 1.27)
					(thickness 0.15)
				)
			)
		)
		(property "Value" "TP_0.75mm_SMD"
			(at 147.955 128.27 0)
			(effects
				(font
					(size 1.27 1.27)
					(thickness 0.15)
				)
				(justify left bottom)
				(hide yes)
			)
		)
		(property "Footprint" "antmicro-footprints:TP_SMD_0.75mm"
			(at 147.955 125.73 0)
			(effects
				(font
					(size 1.27 1.27)
					(thickness 0.15)
				)
				(justify left bottom)
				(hide yes)
			)
		)
		(property "Datasheet" ""
			(at 140.97 119.38 0)
			(effects
				(font
					(size 1.27 1.27)
					(thickness 0.15)
				)
				(justify left bottom)
				(hide yes)
			)
		)
		(property "Description" "SMT test point"
			(at 158.75 132.08 0)
			(effects
				(font
					(size 1.27 1.27)
				)
				(hide yes)
			)
		)
		(property "MPN" ""
			(at 147.955 120.65 0)
			(effects
				(font
					(size 1.27 1.27)
					(thickness 0.15)
				)
				(justify left bottom)
				(hide yes)
			)
		)
		(property "Manufacturer" ""
			(at 147.955 125.73 0)
			(effects
				(font
					(size 1.27 1.27)
					(thickness 0.15)
				)
				(justify left bottom)
				(hide yes)
			)
		)
		(property "Author" "Antmicro"
			(at 147.955 123.19 0)
			(effects
				(font
					(size 1.27 1.27)
					(thickness 0.15)
				)
				(justify left bottom)
				(hide yes)
			)
		)
		(property "License" "Apache-2.0"
			(at 147.955 120.65 0)
			(effects
				(font
					(size 1.27 1.27)
					(thickness 0.15)
				)
				(justify left bottom)
				(hide yes)
			)
		)
		(property "Public" "False"
			(at 148.59 118.11 0)
			(effects
				(font
					(size 1.27 1.27)
				)
				(justify left bottom)
				(hide yes)
			)
		)
		(pin "1"
		)
		(instances
			(project "polarfire-som"
				(path ""
					(reference "TP25")
					(unit 1)
				)
			)
		)
	)
	(symbol
		(lib_id "antmicropower:VDDI")
		(at 50.8 62.23 90)
		(unit 1)
		(exclude_from_sim no)
		(in_bom yes)
		(on_board yes)
		(dnp no)
		(fields_autoplaced yes)
		(property "Reference" "#PWR0320"
			(at 54.61 62.23 0)
			(effects
				(font
					(size 1.27 1.27)
				)
				(hide yes)
			)
		)
		(property "Value" "VDD"
			(at 47.625 62.23 90)
			(effects
				(font
					(size 1.27 1.27)
				)
				(justify left)
			)
		)
		(property "Footprint" ""
			(at 50.8 62.23 0)
			(effects
				(font
					(size 1.27 1.27)
				)
				(hide yes)
			)
		)
		(property "Datasheet" ""
			(at 50.8 62.23 0)
			(effects
				(font
					(size 1.27 1.27)
				)
				(hide yes)
			)
		)
		(property "Description" ""
			(at 50.8 62.23 0)
			(effects
				(font
					(size 1.27 1.27)
				)
				(hide yes)
			)
		)
		(pin "1"
		)
		(instances
			(project "polarfire-som"
				(path ""
					(reference "#PWR0320")
					(unit 1)
				)
			)
		)
	)
	(symbol
		(lib_id "antmicroResistors0402:R_0R_0402")
		(at 102.87 59.69 180)
		(unit 1)
		(exclude_from_sim no)
		(in_bom yes)
		(on_board yes)
		(dnp no)
		(property "Reference" "R97"
			(at 96.52 58.42 0)
			(effects
				(font
					(size 1.27 1.27)
					(thickness 0.15)
				)
			)
		)
		(property "Value" "R_0R_0402"
			(at 82.55 46.99 0)
			(effects
				(font
					(size 1.27 1.27)
					(thickness 0.15)
				)
				(justify left bottom)
				(hide yes)
			)
		)
		(property "Footprint" "antmicro-footprints:R_0402_1005Metric"
			(at 82.55 44.45 0)
			(effects
				(font
					(size 1.27 1.27)
					(thickness 0.15)
				)
				(justify left bottom)
				(hide yes)
			)
		)
		(property "Datasheet" "https://industrial.panasonic.com/cdbs/www-data/pdf/RDA0000/AOA0000C301.pdf"
			(at 82.55 41.91 0)
			(effects
				(font
					(size 1.27 1.27)
					(thickness 0.15)
				)
				(justify left bottom)
				(hide yes)
			)
		)
		(property "Description" "SMD Chip Resistor, Jumper, 0 ohm, 100 mW, 0402 [1005 Metric], Thick Film, General Purpose"
			(at 102.87 59.69 0)
			(effects
				(font
					(size 1.27 1.27)
				)
				(hide yes)
			)
		)
		(property "MPN" "ERJ2GE0R00X"
			(at 82.55 39.37 0)
			(effects
				(font
					(size 1.27 1.27)
					(thickness 0.15)
				)
				(justify left bottom)
				(hide yes)
			)
		)
		(property "Manufacturer" "Panasonic"
			(at 82.55 36.83 0)
			(effects
				(font
					(size 1.27 1.27)
					(thickness 0.15)
				)
				(justify left bottom)
				(hide yes)
			)
		)
		(property "License" "Apache-2.0"
			(at 82.55 34.29 0)
			(effects
				(font
					(size 1.27 1.27)
					(thickness 0.15)
				)
				(justify left bottom)
				(hide yes)
			)
		)
		(property "Author" "Antmicro"
			(at 82.55 31.75 0)
			(effects
				(font
					(size 1.27 1.27)
					(thickness 0.15)
				)
				(justify left bottom)
				(hide yes)
			)
		)
		(property "Val" "0R"
			(at 104.14 58.42 0)
			(effects
				(font
					(size 1.27 1.27)
					(thickness 0.15)
				)
			)
		)
		(property "Tolerance" "~"
			(at 82.55 49.53 0)
			(effects
				(font
					(size 1.27 1.27)
				)
				(justify left bottom)
				(hide yes)
			)
		)
		(property "Current" "1A"
			(at 82.55 29.21 0)
			(effects
				(font
					(size 1.27 1.27)
					(thickness 0.15)
				)
				(justify left bottom)
				(hide yes)
			)
		)
		(property "Public" ""
			(at 82.55 29.21 0)
			(effects
				(font
					(size 1.27 1.27)
				)
				(justify left bottom)
				(hide yes)
			)
		)
		(pin "1"
		)
		(pin "2"
		)
		(instances
			(project "polarfire-som"
				(path ""
					(reference "R97")
					(unit 1)
				)
			)
		)
	)
	(symbol
		(lib_id "antmicroTestPoints:TP_0.75mm_SMD")
		(at 279.4 148.59 0)
		(unit 1)
		(exclude_from_sim no)
		(in_bom no)
		(on_board yes)
		(dnp no)
		(property "Reference" "TP22"
			(at 286.385 148.59 0)
			(effects
				(font
					(size 1.27 1.27)
					(thickness 0.15)
				)
			)
		)
		(property "Value" "TP_0.75mm_SMD"
			(at 290.195 152.4 0)
			(effects
				(font
					(size 1.27 1.27)
					(thickness 0.15)
				)
				(justify left bottom)
				(hide yes)
			)
		)
		(property "Footprint" "antmicro-footprints:TP_SMD_0.75mm"
			(at 290.195 154.94 0)
			(effects
				(font
					(size 1.27 1.27)
					(thickness 0.15)
				)
				(justify left bottom)
				(hide yes)
			)
		)
		(property "Datasheet" ""
			(at 297.18 161.29 0)
			(effects
				(font
					(size 1.27 1.27)
					(thickness 0.15)
				)
				(justify left bottom)
				(hide yes)
			)
		)
		(property "Description" "SMT test point"
			(at 279.4 148.59 0)
			(effects
				(font
					(size 1.27 1.27)
				)
				(hide yes)
			)
		)
		(property "MPN" ""
			(at 290.195 160.02 0)
			(effects
				(font
					(size 1.27 1.27)
					(thickness 0.15)
				)
				(justify left bottom)
				(hide yes)
			)
		)
		(property "Manufacturer" ""
			(at 290.195 154.94 0)
			(effects
				(font
					(size 1.27 1.27)
					(thickness 0.15)
				)
				(justify left bottom)
				(hide yes)
			)
		)
		(property "Author" "Antmicro"
			(at 290.195 157.48 0)
			(effects
				(font
					(size 1.27 1.27)
					(thickness 0.15)
				)
				(justify left bottom)
				(hide yes)
			)
		)
		(property "License" "Apache-2.0"
			(at 290.195 160.02 0)
			(effects
				(font
					(size 1.27 1.27)
					(thickness 0.15)
				)
				(justify left bottom)
				(hide yes)
			)
		)
		(property "Public" "False"
			(at 289.56 162.56 0)
			(effects
				(font
					(size 1.27 1.27)
				)
				(justify left bottom)
				(hide yes)
			)
		)
		(pin "1"
		)
		(instances
			(project "polarfire-som"
				(path ""
					(reference "TP22")
					(unit 1)
				)
			)
		)
	)
	(symbol
		(lib_id "antmicropower:GND")
		(at 156.21 148.59 0)
		(unit 1)
		(exclude_from_sim no)
		(in_bom yes)
		(on_board yes)
		(dnp no)
		(property "Reference" "#PWR361"
			(at 165.1 151.13 0)
			(effects
				(font
					(size 1.27 1.27)
					(thickness 0.15)
				)
				(justify left bottom)
				(hide yes)
			)
		)
		(property "Value" "GND"
			(at 156.21 153.67 0)
			(effects
				(font
					(size 1.27 1.27)
					(thickness 0.15)
				)
			)
		)
		(property "Footprint" ""
			(at 165.1 156.21 0)
			(effects
				(font
					(size 1.27 1.27)
					(thickness 0.15)
				)
				(justify left bottom)
				(hide yes)
			)
		)
		(property "Datasheet" ""
			(at 165.1 161.29 0)
			(effects
				(font
					(size 1.27 1.27)
					(thickness 0.15)
				)
				(justify left bottom)
				(hide yes)
			)
		)
		(property "Description" ""
			(at 156.21 148.59 0)
			(effects
				(font
					(size 1.27 1.27)
				)
				(hide yes)
			)
		)
		(property "Author" "Antmicro"
			(at 165.1 156.21 0)
			(effects
				(font
					(size 1.27 1.27)
					(thickness 0.15)
				)
				(justify left bottom)
				(hide yes)
			)
		)
		(property "License" "Apache-2.0"
			(at 165.1 158.75 0)
			(effects
				(font
					(size 1.27 1.27)
					(thickness 0.15)
				)
				(justify left bottom)
				(hide yes)
			)
		)
		(pin "1"
		)
		(instances
			(project "polarfire-som"
				(path ""
					(reference "#PWR361")
					(unit 1)
				)
			)
		)
	)
	(symbol
		(lib_id "antmicroCapacitors0402:C_10u_10V_0402")
		(at 262.89 151.13 90)
		(unit 1)
		(exclude_from_sim no)
		(in_bom yes)
		(on_board yes)
		(dnp no)
		(fields_autoplaced yes)
		(property "Reference" "C112"
			(at 265.43 147.3136 90)
			(effects
				(font
					(size 1.27 1.27)
					(thickness 0.15)
				)
				(justify right)
			)
		)
		(property "Value" "C_10u_10V_0402"
			(at 273.05 130.81 0)
			(effects
				(font
					(size 1.27 1.27)
					(thickness 0.15)
				)
				(justify left bottom)
				(hide yes)
			)
		)
		(property "Footprint" "antmicro-footprints:C_0402_1005Metric"
			(at 275.59 130.81 0)
			(effects
				(font
					(size 1.27 1.27)
					(thickness 0.15)
				)
				(justify left bottom)
				(hide yes)
			)
		)
		(property "Datasheet" "https://www.murata.com/products/productdetail?partno=GRM155R61A106ME11%23"
			(at 278.13 130.81 0)
			(effects
				(font
					(size 1.27 1.27)
					(thickness 0.15)
				)
				(justify left bottom)
				(hide yes)
			)
		)
		(property "Description" "Multilayer Ceramic Capacitors MLCC - SMD/SMT 10 uF 10 VDC 20% 0402 X5R"
			(at 262.89 151.13 0)
			(effects
				(font
					(size 1.27 1.27)
				)
				(hide yes)
			)
		)
		(property "MPN" "GRM155R61A106ME11D"
			(at 280.67 130.81 0)
			(effects
				(font
					(size 1.27 1.27)
					(thickness 0.15)
				)
				(justify left bottom)
				(hide yes)
			)
		)
		(property "Manufacturer" "Murata"
			(at 283.21 130.81 0)
			(effects
				(font
					(size 1.27 1.27)
					(thickness 0.15)
				)
				(justify left bottom)
				(hide yes)
			)
		)
		(property "License" "Apache-2.0"
			(at 285.75 130.81 0)
			(effects
				(font
					(size 1.27 1.27)
					(thickness 0.15)
				)
				(justify left bottom)
				(hide yes)
			)
		)
		(property "Author" "Antmicro"
			(at 288.29 130.81 0)
			(effects
				(font
					(size 1.27 1.27)
					(thickness 0.15)
				)
				(justify left bottom)
				(hide yes)
			)
		)
		(property "Val" "10u"
			(at 265.43 149.8536 90)
			(effects
				(font
					(size 1.27 1.27)
					(thickness 0.15)
				)
				(justify right)
			)
		)
		(property "Voltage" "10V"
			(at 290.83 130.81 0)
			(effects
				(font
					(size 1.27 1.27)
				)
				(justify left bottom)
				(hide yes)
			)
		)
		(property "Dielectric" "X5R"
			(at 293.37 130.81 0)
			(effects
				(font
					(size 1.27 1.27)
				)
				(justify left bottom)
				(hide yes)
			)
		)
		(property "Public" ""
			(at 295.91 130.81 0)
			(effects
				(font
					(size 1.27 1.27)
				)
				(justify left bottom)
				(hide yes)
			)
		)
		(pin "1"
		)
		(pin "2"
		)
		(instances
			(project "polarfire-som"
				(path ""
					(reference "C112")
					(unit 1)
				)
			)
		)
	)
	(symbol
		(lib_id "antmicroFixedInductors:L_1u_3.2A_0805")
		(at 248.92 45.72 0)
		(unit 1)
		(exclude_from_sim no)
		(in_bom yes)
		(on_board yes)
		(dnp no)
		(fields_autoplaced yes)
		(property "Reference" "L2"
			(at 251.46 40.64 0)
			(effects
				(font
					(size 1.27 1.27)
					(thickness 0.15)
				)
			)
		)
		(property "Value" "L_1u_3.2A_0805"
			(at 262.89 48.26 0)
			(effects
				(font
					(size 1.27 1.27)
					(thickness 0.15)
				)
				(justify left bottom)
				(hide yes)
			)
		)
		(property "Footprint" "antmicro-footprints:L_0805_2012Metric"
			(at 262.89 53.34 0)
			(effects
				(font
					(size 1.27 1.27)
					(thickness 0.15)
				)
				(justify left bottom)
				(hide yes)
			)
		)
		(property "Datasheet" "https://abracon.com/datasheets/AOTA-B201208S.pdf"
			(at 262.89 55.88 0)
			(effects
				(font
					(size 1.27 1.27)
					(thickness 0.15)
				)
				(justify left bottom)
				(hide yes)
			)
		)
		(property "Description" "Power Inductor (SMT), 1 µH, 0.05 ohm, 3.2 A, AOTA-B201208S"
			(at 248.92 45.72 0)
			(effects
				(font
					(size 1.27 1.27)
				)
				(hide yes)
			)
		)
		(property "Val" "1u/3.2A"
			(at 251.46 43.18 0)
			(effects
				(font
					(size 1.27 1.27)
					(thickness 0.15)
				)
			)
		)
		(property "Manufacturer" "Abracon"
			(at 262.89 58.42 0)
			(effects
				(font
					(size 1.27 1.27)
					(thickness 0.15)
				)
				(justify left bottom)
				(hide yes)
			)
		)
		(property "MPN" "AOTA-B201208S1R0MT "
			(at 262.89 60.96 0)
			(effects
				(font
					(size 1.27 1.27)
					(thickness 0.15)
				)
				(justify left bottom)
				(hide yes)
			)
		)
		(property "ISat" "3.5 A"
			(at 262.89 62.23 0)
			(effects
				(font
					(size 1.27 1.27)
				)
				(justify left)
				(hide yes)
			)
		)
		(property "IMax" "3.2 A"
			(at 262.89 66.04 0)
			(effects
				(font
					(size 1.27 1.27)
					(thickness 0.15)
				)
				(justify left bottom)
				(hide yes)
			)
		)
		(property "Size" "2x1.2"
			(at 262.89 68.58 0)
			(effects
				(font
					(size 1.27 1.27)
					(thickness 0.15)
				)
				(justify left bottom)
				(hide yes)
			)
		)
		(property "Author" "Antmicro"
			(at 262.89 71.12 0)
			(effects
				(font
					(size 1.27 1.27)
					(thickness 0.15)
				)
				(justify left bottom)
				(hide yes)
			)
		)
		(property "License" "Apache-2.0"
			(at 262.89 73.66 0)
			(effects
				(font
					(size 1.27 1.27)
					(thickness 0.15)
				)
				(justify left bottom)
				(hide yes)
			)
		)
		(property "Public" ""
			(at 262.89 76.2 0)
			(effects
				(font
					(size 1.27 1.27)
				)
				(justify left bottom)
				(hide yes)
			)
		)
		(pin "1"
		)
		(pin "2"
		)
		(instances
			(project "polarfire-som"
				(path ""
					(reference "L2")
					(unit 1)
				)
			)
		)
	)
	(symbol
		(lib_id "antmicropower:GND")
		(at 262.89 152.4 0)
		(unit 1)
		(exclude_from_sim no)
		(in_bom yes)
		(on_board yes)
		(dnp no)
		(property "Reference" "#PWR073"
			(at 271.78 154.94 0)
			(effects
				(font
					(size 1.27 1.27)
					(thickness 0.15)
				)
				(justify left bottom)
				(hide yes)
			)
		)
		(property "Value" "GND"
			(at 262.89 157.48 0)
			(effects
				(font
					(size 1.27 1.27)
					(thickness 0.15)
				)
			)
		)
		(property "Footprint" ""
			(at 271.78 160.02 0)
			(effects
				(font
					(size 1.27 1.27)
					(thickness 0.15)
				)
				(justify left bottom)
				(hide yes)
			)
		)
		(property "Datasheet" ""
			(at 271.78 165.1 0)
			(effects
				(font
					(size 1.27 1.27)
					(thickness 0.15)
				)
				(justify left bottom)
				(hide yes)
			)
		)
		(property "Description" ""
			(at 262.89 152.4 0)
			(effects
				(font
					(size 1.27 1.27)
				)
				(hide yes)
			)
		)
		(property "Author" "Antmicro"
			(at 271.78 160.02 0)
			(effects
				(font
					(size 1.27 1.27)
					(thickness 0.15)
				)
				(justify left bottom)
				(hide yes)
			)
		)
		(property "License" "Apache-2.0"
			(at 271.78 162.56 0)
			(effects
				(font
					(size 1.27 1.27)
					(thickness 0.15)
				)
				(justify left bottom)
				(hide yes)
			)
		)
		(pin "1"
		)
		(instances
			(project "polarfire-som"
				(path ""
					(reference "#PWR073")
					(unit 1)
				)
			)
		)
	)
	(symbol
		(lib_id "antmicropower:GND")
		(at 189.23 237.49 0)
		(unit 1)
		(exclude_from_sim no)
		(in_bom yes)
		(on_board yes)
		(dnp no)
		(property "Reference" "#PWR090"
			(at 198.12 240.03 0)
			(effects
				(font
					(size 1.27 1.27)
					(thickness 0.15)
				)
				(justify left bottom)
				(hide yes)
			)
		)
		(property "Value" "GND"
			(at 189.23 241.3 0)
			(effects
				(font
					(size 1.27 1.27)
					(thickness 0.15)
				)
			)
		)
		(property "Footprint" ""
			(at 198.12 245.11 0)
			(effects
				(font
					(size 1.27 1.27)
					(thickness 0.15)
				)
				(justify left bottom)
				(hide yes)
			)
		)
		(property "Datasheet" ""
			(at 198.12 250.19 0)
			(effects
				(font
					(size 1.27 1.27)
					(thickness 0.15)
				)
				(justify left bottom)
				(hide yes)
			)
		)
		(property "Description" ""
			(at 189.23 237.49 0)
			(effects
				(font
					(size 1.27 1.27)
				)
				(hide yes)
			)
		)
		(property "Author" "Antmicro"
			(at 198.12 245.11 0)
			(effects
				(font
					(size 1.27 1.27)
					(thickness 0.15)
				)
				(justify left bottom)
				(hide yes)
			)
		)
		(property "License" "Apache-2.0"
			(at 198.12 247.65 0)
			(effects
				(font
					(size 1.27 1.27)
					(thickness 0.15)
				)
				(justify left bottom)
				(hide yes)
			)
		)
		(pin "1"
		)
		(instances
			(project "polarfire-som"
				(path ""
					(reference "#PWR090")
					(unit 1)
				)
			)
		)
	)
	(symbol
		(lib_id "antmicropower:+3V3")
		(at 59.69 50.8 0)
		(unit 1)
		(exclude_from_sim no)
		(in_bom yes)
		(on_board yes)
		(dnp no)
		(property "Reference" "#PWR072"
			(at 74.93 53.34 0)
			(effects
				(font
					(size 1.27 1.27)
					(thickness 0.15)
				)
				(justify left bottom)
				(hide yes)
			)
		)
		(property "Value" "+3V3"
			(at 59.69 46.99 0)
			(effects
				(font
					(size 1.27 1.27)
					(thickness 0.15)
				)
			)
		)
		(property "Footprint" ""
			(at 74.93 58.42 0)
			(effects
				(font
					(size 1.27 1.27)
					(thickness 0.15)
				)
				(justify left bottom)
				(hide yes)
			)
		)
		(property "Datasheet" ""
			(at 74.93 60.96 0)
			(effects
				(font
					(size 1.27 1.27)
					(thickness 0.15)
				)
				(justify left bottom)
				(hide yes)
			)
		)
		(property "Description" ""
			(at 59.69 50.8 0)
			(effects
				(font
					(size 1.27 1.27)
				)
				(hide yes)
			)
		)
		(property "Author" "Antmicro"
			(at 74.93 58.42 0)
			(effects
				(font
					(size 1.27 1.27)
					(thickness 0.15)
				)
				(justify left bottom)
				(hide yes)
			)
		)
		(property "License" "Apache-2.0"
			(at 74.93 60.96 0)
			(effects
				(font
					(size 1.27 1.27)
					(thickness 0.15)
				)
				(justify left bottom)
				(hide yes)
			)
		)
		(pin "1"
		)
		(instances
			(project "polarfire-som"
				(path ""
					(reference "#PWR072")
					(unit 1)
				)
			)
		)
	)
	(symbol
		(lib_id "antmicroResistors0603:R_0R01_0603")
		(at 289.56 45.72 0)
		(unit 1)
		(exclude_from_sim no)
		(in_bom yes)
		(on_board yes)
		(dnp no)
		(fields_autoplaced yes)
		(property "Reference" "R21"
			(at 292.1 39.37 0)
			(effects
				(font
					(size 1.27 1.27)
					(thickness 0.15)
				)
			)
		)
		(property "Value" "R_0R01_0603"
			(at 309.88 58.42 0)
			(effects
				(font
					(size 1.27 1.27)
					(thickness 0.15)
				)
				(justify left bottom)
				(hide yes)
			)
		)
		(property "Footprint" "antmicro-footprints:R_0603_1608Metric"
			(at 309.88 60.96 0)
			(effects
				(font
					(size 1.27 1.27)
					(thickness 0.15)
				)
				(justify left bottom)
				(hide yes)
			)
		)
		(property "Datasheet" "https://www.bourns.com/docs/product-datasheets/cfn-a.pdf"
			(at 309.88 63.5 0)
			(effects
				(font
					(size 1.27 1.27)
					(thickness 0.15)
				)
				(justify left bottom)
				(hide yes)
			)
		)
		(property "Description" "SMD Chip Resistor, 10 mohm, ± 1%, 0.5 W, 0603 [1608 Metric], Metal Foil, Current Sensing"
			(at 289.56 45.72 0)
			(effects
				(font
					(size 1.27 1.27)
				)
				(hide yes)
			)
		)
		(property "MPN" "CFN0603AFZ-R010ELF"
			(at 309.88 66.04 0)
			(effects
				(font
					(size 1.27 1.27)
					(thickness 0.15)
				)
				(justify left bottom)
				(hide yes)
			)
		)
		(property "Manufacturer" "Bourns"
			(at 309.88 68.58 0)
			(effects
				(font
					(size 1.27 1.27)
					(thickness 0.15)
				)
				(justify left bottom)
				(hide yes)
			)
		)
		(property "License" "Apache-2.0"
			(at 309.88 71.12 0)
			(effects
				(font
					(size 1.27 1.27)
					(thickness 0.15)
				)
				(justify left bottom)
				(hide yes)
			)
		)
		(property "Author" "Antmicro"
			(at 309.88 73.66 0)
			(effects
				(font
					(size 1.27 1.27)
					(thickness 0.15)
				)
				(justify left bottom)
				(hide yes)
			)
		)
		(property "Val" "0R01"
			(at 292.1 41.91 0)
			(effects
				(font
					(size 1.27 1.27)
					(thickness 0.15)
				)
			)
		)
		(property "Tolerance" "1%"
			(at 309.88 55.88 0)
			(effects
				(font
					(size 1.27 1.27)
				)
				(justify left bottom)
				(hide yes)
			)
		)
		(property "Public" ""
			(at 309.88 76.2 0)
			(effects
				(font
					(size 1.27 1.27)
				)
				(justify left bottom)
				(hide yes)
			)
		)
		(pin "1"
		)
		(pin "2"
		)
		(instances
			(project "polarfire-som"
				(path ""
					(reference "R21")
					(unit 1)
				)
			)
		)
	)
	(symbol
		(lib_id "antmicroLEDIndicationDiscrete:LED_G_0603_LTST-C190GKT")
		(at 365.76 133.35 90)
		(unit 1)
		(exclude_from_sim no)
		(in_bom yes)
		(on_board yes)
		(dnp no)
		(property "Reference" "D5"
			(at 359.41 130.81 90)
			(effects
				(font
					(size 1.27 1.27)
					(thickness 0.15)
				)
				(justify right)
			)
		)
		(property "Value" "LED_G_0603_LTST-C190GKT"
			(at 367.284 130.81 90)
			(effects
				(font
					(size 1.27 1.27)
					(thickness 0.15)
				)
				(justify right)
			)
		)
		(property "Footprint" "antmicro-footprints:LED_0603_1608Metric_G"
			(at 375.92 110.49 0)
			(effects
				(font
					(size 1.27 1.27)
					(thickness 0.15)
				)
				(justify left bottom)
				(hide yes)
			)
		)
		(property "Datasheet" "https://media.digikey.com/pdf/Data%20Sheets/Lite-On%20PDFs/LTST-C190GKT.pdf"
			(at 378.46 110.49 0)
			(effects
				(font
					(size 1.27 1.27)
					(thickness 0.15)
				)
				(justify left bottom)
				(hide yes)
			)
		)
		(property "Description" "LED, Green, SMD, 0603, 20 mA, 2.1 V, 569 nm"
			(at 365.76 133.35 0)
			(effects
				(font
					(size 1.27 1.27)
				)
				(hide yes)
			)
		)
		(property "MPN" "LTST-C190GKT"
			(at 381 110.49 0)
			(effects
				(font
					(size 1.27 1.27)
					(thickness 0.15)
				)
				(justify left bottom)
				(hide yes)
			)
		)
		(property "Manufacturer" "Lite-On"
			(at 383.54 110.49 0)
			(effects
				(font
					(size 1.27 1.27)
					(thickness 0.15)
				)
				(justify left bottom)
				(hide yes)
			)
		)
		(property "Author" "Antmicro"
			(at 386.08 110.49 0)
			(effects
				(font
					(size 1.27 1.27)
					(thickness 0.15)
				)
				(justify left bottom)
				(hide yes)
			)
		)
		(property "License" "Apache-2.0"
			(at 388.62 110.49 0)
			(effects
				(font
					(size 1.27 1.27)
					(thickness 0.15)
				)
				(justify left bottom)
				(hide yes)
			)
		)
		(property "VSD_class" "LED"
			(at 391.16 110.49 0)
			(effects
				(font
					(size 1.27 1.27)
				)
				(justify left bottom)
				(hide yes)
			)
		)
		(property "Color" "Green"
			(at 370.84 110.49 0)
			(effects
				(font
					(size 1.27 1.27)
				)
				(justify left bottom)
				(hide yes)
			)
		)
		(property "Public" ""
			(at 383.54 113.03 0)
			(effects
				(font
					(size 1.27 1.27)
				)
				(justify left bottom)
				(hide yes)
			)
		)
		(pin "2"
		)
		(pin "1"
		)
		(instances
			(project "polarfire-som"
				(path ""
					(reference "D5")
					(unit 1)
				)
			)
		)
	)
	(symbol
		(lib_id "antmicropower:+2V5")
		(at 53.34 250.19 0)
		(unit 1)
		(exclude_from_sim no)
		(in_bom yes)
		(on_board yes)
		(dnp no)
		(fields_autoplaced yes)
		(property "Reference" "#PWR066"
			(at 53.34 254 0)
			(effects
				(font
					(size 1.27 1.27)
				)
				(hide yes)
			)
		)
		(property "Value" "+2V5"
			(at 53.34 245.11 0)
			(effects
				(font
					(size 1.27 1.27)
				)
			)
		)
		(property "Footprint" ""
			(at 53.34 250.19 0)
			(effects
				(font
					(size 1.27 1.27)
				)
				(hide yes)
			)
		)
		(property "Datasheet" ""
			(at 53.34 250.19 0)
			(effects
				(font
					(size 1.27 1.27)
				)
				(hide yes)
			)
		)
		(property "Description" ""
			(at 53.34 250.19 0)
			(effects
				(font
					(size 1.27 1.27)
				)
				(hide yes)
			)
		)
		(pin "1"
		)
		(instances
			(project "polarfire-som"
				(path ""
					(reference "#PWR066")
					(unit 1)
				)
			)
		)
	)
	(symbol
		(lib_id "antmicroResistors0402:R_0R_0402")
		(at 279.4 127 0)
		(unit 1)
		(exclude_from_sim no)
		(in_bom yes)
		(on_board yes)
		(dnp no)
		(property "Reference" "R78"
			(at 281.94 121.92 0)
			(effects
				(font
					(size 1.27 1.27)
					(thickness 0.15)
				)
			)
		)
		(property "Value" "R_0R_0402"
			(at 299.72 139.7 0)
			(effects
				(font
					(size 1.27 1.27)
					(thickness 0.15)
				)
				(justify left bottom)
				(hide yes)
			)
		)
		(property "Footprint" "antmicro-footprints:R_0402_1005Metric"
			(at 299.72 142.24 0)
			(effects
				(font
					(size 1.27 1.27)
					(thickness 0.15)
				)
				(justify left bottom)
				(hide yes)
			)
		)
		(property "Datasheet" "https://industrial.panasonic.com/cdbs/www-data/pdf/RDA0000/AOA0000C301.pdf"
			(at 299.72 144.78 0)
			(effects
				(font
					(size 1.27 1.27)
					(thickness 0.15)
				)
				(justify left bottom)
				(hide yes)
			)
		)
		(property "Description" "SMD Chip Resistor, Jumper, 0 ohm, 100 mW, 0402 [1005 Metric], Thick Film, General Purpose"
			(at 279.4 127 0)
			(effects
				(font
					(size 1.27 1.27)
				)
				(hide yes)
			)
		)
		(property "MPN" "ERJ2GE0R00X"
			(at 299.72 147.32 0)
			(effects
				(font
					(size 1.27 1.27)
					(thickness 0.15)
				)
				(justify left bottom)
				(hide yes)
			)
		)
		(property "Manufacturer" "Panasonic"
			(at 299.72 149.86 0)
			(effects
				(font
					(size 1.27 1.27)
					(thickness 0.15)
				)
				(justify left bottom)
				(hide yes)
			)
		)
		(property "License" "Apache-2.0"
			(at 299.72 152.4 0)
			(effects
				(font
					(size 1.27 1.27)
					(thickness 0.15)
				)
				(justify left bottom)
				(hide yes)
			)
		)
		(property "Author" "Antmicro"
			(at 299.72 154.94 0)
			(effects
				(font
					(size 1.27 1.27)
					(thickness 0.15)
				)
				(justify left bottom)
				(hide yes)
			)
		)
		(property "Val" "0R"
			(at 281.94 124.46 0)
			(effects
				(font
					(size 1.27 1.27)
					(thickness 0.15)
				)
			)
		)
		(property "Tolerance" "~"
			(at 299.72 137.16 0)
			(effects
				(font
					(size 1.27 1.27)
				)
				(justify left bottom)
				(hide yes)
			)
		)
		(property "Current" "1A"
			(at 299.72 157.48 0)
			(effects
				(font
					(size 1.27 1.27)
					(thickness 0.15)
				)
				(justify left bottom)
				(hide yes)
			)
		)
		(property "Public" ""
			(at 299.72 157.48 0)
			(effects
				(font
					(size 1.27 1.27)
				)
				(justify left bottom)
				(hide yes)
			)
		)
		(pin "1"
		)
		(pin "2"
		)
		(instances
			(project "polarfire-som"
				(path ""
					(reference "R78")
					(unit 1)
				)
			)
		)
	)
	(symbol
		(lib_id "antmicroTVSDiodes:AXGD10402KR")
		(at 63.5 143.51 90)
		(unit 1)
		(exclude_from_sim no)
		(in_bom yes)
		(on_board yes)
		(dnp no)
		(property "Reference" "D1"
			(at 66.04 139.7 90)
			(effects
				(font
					(size 1.27 1.27)
					(thickness 0.15)
				)
				(justify right)
			)
		)
		(property "Value" "AXGD10402KR"
			(at 73.66 118.11 0)
			(effects
				(font
					(size 1.27 1.27)
					(thickness 0.15)
				)
				(justify left bottom)
				(hide yes)
			)
		)
		(property "Footprint" "antmicro-footprints:D_0402_1005Metric"
			(at 76.2 118.11 0)
			(effects
				(font
					(size 1.27 1.27)
					(thickness 0.15)
				)
				(justify left bottom)
				(hide yes)
			)
		)
		(property "Datasheet" "https://www.littelfuse.com/media?resourcetype=datasheets&itemid=020b2bf2-064c-4ff1-a898-b4ec805b2fea&filename=littelfuse-xtremeguard-axgd-datasheet"
			(at 78.74 118.11 0)
			(effects
				(font
					(size 1.27 1.27)
					(thickness 0.15)
				)
				(justify left bottom)
				(hide yes)
			)
		)
		(property "Description" "Bidirectional TVS, 30 kV,  0402, 24 V, 0.04 pF"
			(at 63.5 143.51 0)
			(effects
				(font
					(size 1.27 1.27)
				)
				(hide yes)
			)
		)
		(property "Manufacturer" "Littelfuse"
			(at 81.28 118.11 0)
			(effects
				(font
					(size 1.27 1.27)
					(thickness 0.15)
				)
				(justify left bottom)
				(hide yes)
			)
		)
		(property "MPN" "AXGD10402KR"
			(at 66.04 142.24 90)
			(effects
				(font
					(size 1.27 1.27)
					(thickness 0.15)
				)
				(justify right)
			)
		)
		(property "Author" "Antmicro"
			(at 83.82 118.11 0)
			(effects
				(font
					(size 1.27 1.27)
					(thickness 0.15)
				)
				(justify left bottom)
				(hide yes)
			)
		)
		(property "License" "Apache-2.0"
			(at 86.36 118.11 0)
			(effects
				(font
					(size 1.27 1.27)
					(thickness 0.15)
				)
				(justify left bottom)
				(hide yes)
			)
		)
		(property "Public" ""
			(at 81.28 123.19 0)
			(effects
				(font
					(size 1.27 1.27)
				)
				(justify left bottom)
				(hide yes)
			)
		)
		(pin "1"
		)
		(pin "2"
		)
		(instances
			(project "polarfire-som"
				(path ""
					(reference "D1")
					(unit 1)
				)
			)
		)
	)
	(symbol
		(lib_id "antmicroResistors0402:R_10k_0402")
		(at 91.44 212.09 90)
		(unit 1)
		(exclude_from_sim no)
		(in_bom yes)
		(on_board yes)
		(dnp no)
		(fields_autoplaced yes)
		(property "Reference" "R10"
			(at 93.345 208.2799 90)
			(effects
				(font
					(size 1.27 1.27)
					(thickness 0.15)
				)
				(justify right)
			)
		)
		(property "Value" "R_10k_0402"
			(at 104.14 191.77 0)
			(effects
				(font
					(size 1.27 1.27)
					(thickness 0.15)
				)
				(justify left bottom)
				(hide yes)
			)
		)
		(property "Footprint" "antmicro-footprints:R_0402_1005Metric"
			(at 106.68 191.77 0)
			(effects
				(font
					(size 1.27 1.27)
					(thickness 0.15)
				)
				(justify left bottom)
				(hide yes)
			)
		)
		(property "Datasheet" "https://www.bourns.com/docs/product-datasheets/cr.pdf"
			(at 109.22 191.77 0)
			(effects
				(font
					(size 1.27 1.27)
					(thickness 0.15)
				)
				(justify left bottom)
				(hide yes)
			)
		)
		(property "Description" "SMD Chip Resistor, 10 kohm, ± 1%, 62.5 mW, 0402 [1005 Metric], Thick Film, General Purpose"
			(at 91.44 212.09 0)
			(effects
				(font
					(size 1.27 1.27)
				)
				(hide yes)
			)
		)
		(property "MPN" "CR0402-FX-1002GLF"
			(at 111.76 191.77 0)
			(effects
				(font
					(size 1.27 1.27)
					(thickness 0.15)
				)
				(justify left bottom)
				(hide yes)
			)
		)
		(property "Manufacturer" "Bourns"
			(at 114.3 191.77 0)
			(effects
				(font
					(size 1.27 1.27)
					(thickness 0.15)
				)
				(justify left bottom)
				(hide yes)
			)
		)
		(property "License" "Apache-2.0"
			(at 116.84 191.77 0)
			(effects
				(font
					(size 1.27 1.27)
					(thickness 0.15)
				)
				(justify left bottom)
				(hide yes)
			)
		)
		(property "Author" "Antmicro"
			(at 119.38 191.77 0)
			(effects
				(font
					(size 1.27 1.27)
					(thickness 0.15)
				)
				(justify left bottom)
				(hide yes)
			)
		)
		(property "Val" "10k"
			(at 93.345 210.8199 90)
			(effects
				(font
					(size 1.27 1.27)
					(thickness 0.15)
				)
				(justify right)
			)
		)
		(property "Tolerance" "1%"
			(at 101.6 191.77 0)
			(effects
				(font
					(size 1.27 1.27)
				)
				(justify left bottom)
				(hide yes)
			)
		)
		(property "Public" ""
			(at 121.92 191.77 0)
			(effects
				(font
					(size 1.27 1.27)
				)
				(justify left bottom)
				(hide yes)
			)
		)
		(pin "1"
		)
		(pin "2"
		)
		(instances
			(project "polarfire-som"
				(path ""
					(reference "R10")
					(unit 1)
				)
			)
		)
	)
	(symbol
		(lib_id "antmicroCapacitors0402:C_22u_0402")
		(at 270.51 52.07 90)
		(unit 1)
		(exclude_from_sim no)
		(in_bom yes)
		(on_board yes)
		(dnp no)
		(fields_autoplaced yes)
		(property "Reference" "C106"
			(at 273.05 48.2536 90)
			(effects
				(font
					(size 1.27 1.27)
					(thickness 0.15)
				)
				(justify right)
			)
		)
		(property "Value" "C_22u_0402"
			(at 280.67 31.75 0)
			(effects
				(font
					(size 1.27 1.27)
					(thickness 0.15)
				)
				(justify left bottom)
				(hide yes)
			)
		)
		(property "Footprint" "antmicro-footprints:C_0402_1005Metric"
			(at 283.21 31.75 0)
			(effects
				(font
					(size 1.27 1.27)
					(thickness 0.15)
				)
				(justify left bottom)
				(hide yes)
			)
		)
		(property "Datasheet" "https://www.murata.com/products/productdetail?partno=GRM158R60J226ME01%23"
			(at 285.75 31.75 0)
			(effects
				(font
					(size 1.27 1.27)
					(thickness 0.15)
				)
				(justify left bottom)
				(hide yes)
			)
		)
		(property "Description" "SMD Multilayer Ceramic Capacitor, 22 uF, 4 V, 0402 [1005 Metric], X6S"
			(at 270.51 52.07 0)
			(effects
				(font
					(size 1.27 1.27)
				)
				(hide yes)
			)
		)
		(property "MPN" "GRM158R60J226ME01D"
			(at 288.29 31.75 0)
			(effects
				(font
					(size 1.27 1.27)
					(thickness 0.15)
				)
				(justify left bottom)
				(hide yes)
			)
		)
		(property "Manufacturer" "Murata"
			(at 290.83 31.75 0)
			(effects
				(font
					(size 1.27 1.27)
					(thickness 0.15)
				)
				(justify left bottom)
				(hide yes)
			)
		)
		(property "License" "Apache-2.0"
			(at 293.37 31.75 0)
			(effects
				(font
					(size 1.27 1.27)
					(thickness 0.15)
				)
				(justify left bottom)
				(hide yes)
			)
		)
		(property "Author" "Antmicro"
			(at 295.91 31.75 0)
			(effects
				(font
					(size 1.27 1.27)
					(thickness 0.15)
				)
				(justify left bottom)
				(hide yes)
			)
		)
		(property "Val" "22u"
			(at 273.05 50.7936 90)
			(effects
				(font
					(size 1.27 1.27)
					(thickness 0.15)
				)
				(justify right)
			)
		)
		(property "Voltage" ""
			(at 298.45 31.75 0)
			(effects
				(font
					(size 1.27 1.27)
				)
				(justify left bottom)
				(hide yes)
			)
		)
		(property "Dielectric" ""
			(at 300.99 31.75 0)
			(effects
				(font
					(size 1.27 1.27)
				)
				(justify left bottom)
				(hide yes)
			)
		)
		(property "Public" ""
			(at 303.53 31.75 0)
			(effects
				(font
					(size 1.27 1.27)
				)
				(justify left bottom)
				(hide yes)
			)
		)
		(pin "2"
		)
		(pin "1"
		)
		(instances
			(project "polarfire-som"
				(path ""
					(reference "C106")
					(unit 1)
				)
			)
		)
	)
	(symbol
		(lib_id "antmicropower:GND")
		(at 209.55 115.57 0)
		(unit 1)
		(exclude_from_sim no)
		(in_bom yes)
		(on_board yes)
		(dnp no)
		(fields_autoplaced yes)
		(property "Reference" "#PWR094"
			(at 218.44 118.11 0)
			(effects
				(font
					(size 1.27 1.27)
					(thickness 0.15)
				)
				(justify left bottom)
				(hide yes)
			)
		)
		(property "Value" "GND"
			(at 209.55 120.65 0)
			(effects
				(font
					(size 1.27 1.27)
					(thickness 0.15)
				)
			)
		)
		(property "Footprint" ""
			(at 218.44 123.19 0)
			(effects
				(font
					(size 1.27 1.27)
					(thickness 0.15)
				)
				(justify left bottom)
				(hide yes)
			)
		)
		(property "Datasheet" ""
			(at 218.44 128.27 0)
			(effects
				(font
					(size 1.27 1.27)
					(thickness 0.15)
				)
				(justify left bottom)
				(hide yes)
			)
		)
		(property "Description" ""
			(at 209.55 115.57 0)
			(effects
				(font
					(size 1.27 1.27)
				)
				(hide yes)
			)
		)
		(property "Author" "Antmicro"
			(at 218.44 123.19 0)
			(effects
				(font
					(size 1.27 1.27)
					(thickness 0.15)
				)
				(justify left bottom)
				(hide yes)
			)
		)
		(property "License" "Apache-2.0"
			(at 218.44 125.73 0)
			(effects
				(font
					(size 1.27 1.27)
					(thickness 0.15)
				)
				(justify left bottom)
				(hide yes)
			)
		)
		(pin "1"
		)
		(instances
			(project "polarfire-som"
				(path ""
					(reference "#PWR094")
					(unit 1)
				)
			)
		)
	)
	(symbol
		(lib_id "antmicroResistors0402:R_30k9_0402")
		(at 20.32 228.6 90)
		(unit 1)
		(exclude_from_sim no)
		(in_bom yes)
		(on_board yes)
		(dnp no)
		(fields_autoplaced yes)
		(property "Reference" "R2"
			(at 22.86 224.7899 90)
			(effects
				(font
					(size 1.27 1.27)
					(thickness 0.15)
				)
				(justify right)
			)
		)
		(property "Value" "R_30k9_0402"
			(at 33.02 208.28 0)
			(effects
				(font
					(size 1.27 1.27)
					(thickness 0.15)
				)
				(justify left bottom)
				(hide yes)
			)
		)
		(property "Footprint" "antmicro-footprints:R_0402_1005Metric"
			(at 35.56 208.28 0)
			(effects
				(font
					(size 1.27 1.27)
					(thickness 0.15)
				)
				(justify left bottom)
				(hide yes)
			)
		)
		(property "Datasheet" "https://www.bourns.com/docs/product-datasheets/cr.pdf"
			(at 38.1 208.28 0)
			(effects
				(font
					(size 1.27 1.27)
					(thickness 0.15)
				)
				(justify left bottom)
				(hide yes)
			)
		)
		(property "Description" "SMD Chip Resistor"
			(at 20.32 228.6 0)
			(effects
				(font
					(size 1.27 1.27)
				)
				(hide yes)
			)
		)
		(property "MPN" "CR0402-FX-3092GLF"
			(at 40.64 208.28 0)
			(effects
				(font
					(size 1.27 1.27)
					(thickness 0.15)
				)
				(justify left bottom)
				(hide yes)
			)
		)
		(property "Manufacturer" "Bourns"
			(at 43.18 208.28 0)
			(effects
				(font
					(size 1.27 1.27)
					(thickness 0.15)
				)
				(justify left bottom)
				(hide yes)
			)
		)
		(property "License" "Apache-2.0"
			(at 45.72 208.28 0)
			(effects
				(font
					(size 1.27 1.27)
					(thickness 0.15)
				)
				(justify left bottom)
				(hide yes)
			)
		)
		(property "Author" "Antmicro"
			(at 48.26 208.28 0)
			(effects
				(font
					(size 1.27 1.27)
					(thickness 0.15)
				)
				(justify left bottom)
				(hide yes)
			)
		)
		(property "Val" "30k9"
			(at 22.86 227.3299 90)
			(effects
				(font
					(size 1.27 1.27)
					(thickness 0.15)
				)
				(justify right)
			)
		)
		(property "Tolerance" "1%"
			(at 30.48 208.28 0)
			(effects
				(font
					(size 1.27 1.27)
				)
				(justify left bottom)
				(hide yes)
			)
		)
		(property "Public" ""
			(at 50.8 208.28 0)
			(effects
				(font
					(size 1.27 1.27)
				)
				(justify left bottom)
				(hide yes)
			)
		)
		(pin "1"
		)
		(pin "2"
		)
		(instances
			(project "polarfire-som"
				(path ""
					(reference "R2")
					(unit 1)
				)
			)
		)
	)
	(symbol
		(lib_id "antmicroPMICVoltageRegulatorsDCDCSwitchingRegulators:MP5424GRM")
		(at 212.09 68.58 0)
		(unit 1)
		(exclude_from_sim no)
		(in_bom yes)
		(on_board yes)
		(dnp no)
		(fields_autoplaced yes)
		(property "Reference" "U7"
			(at 224.79 60.96 0)
			(effects
				(font
					(size 1.27 1.27)
					(thickness 0.15)
				)
			)
		)
		(property "Value" "MP5424GRM"
			(at 224.79 63.5 0)
			(effects
				(font
					(size 1.27 1.27)
					(thickness 0.15)
				)
			)
		)
		(property "Footprint" "antmicro-footprints:QFN-26_3.5x4.5x1mm_P0.45mm"
			(at 254 81.28 0)
			(effects
				(font
					(size 1.27 1.27)
					(thickness 0.15)
				)
				(justify left bottom)
				(hide yes)
			)
		)
		(property "Datasheet" "https://www.monolithicpower.com/en/documentview/productdocument/index/version/2/document_type/Datasheet/lang/en/sku/MP5424GRM/document_id/10311/"
			(at 254 83.82 0)
			(effects
				(font
					(size 1.27 1.27)
					(thickness 0.15)
				)
				(justify left bottom)
				(hide yes)
			)
		)
		(property "Description" "5V PMIC with Four 4.5A/2.5A/4.5A/2A Buck Converters, 3 LDOs, 1 Load Switch and Flexible System Settings via I2C and MTP"
			(at 212.09 68.58 0)
			(effects
				(font
					(size 1.27 1.27)
				)
				(hide yes)
			)
		)
		(property "Author" "Antmicro"
			(at 254 86.36 0)
			(effects
				(font
					(size 1.27 1.27)
					(thickness 0.15)
				)
				(justify left bottom)
				(hide yes)
			)
		)
		(property "License" "Apache-2.0"
			(at 254 88.9 0)
			(effects
				(font
					(size 1.27 1.27)
					(thickness 0.15)
				)
				(justify left bottom)
				(hide yes)
			)
		)
		(property "MPN" "MP5424GRM-0000-Z"
			(at 254 76.2 0)
			(effects
				(font
					(size 1.27 1.27)
					(thickness 0.15)
				)
				(justify left bottom)
				(hide yes)
			)
		)
		(property "Manufacturer" "Monolithic Power Systems"
			(at 254 78.74 0)
			(effects
				(font
					(size 1.27 1.27)
					(thickness 0.15)
				)
				(justify left bottom)
				(hide yes)
			)
		)
		(pin "7"
		)
		(pin "23"
		)
		(pin "16"
		)
		(pin "18"
		)
		(pin "25"
		)
		(pin "8"
		)
		(pin "4"
		)
		(pin "9"
		)
		(pin "5"
		)
		(pin "3"
		)
		(pin "19"
		)
		(pin "26"
		)
		(pin "17"
		)
		(pin "24"
		)
		(pin "20"
		)
		(pin "6"
		)
		(pin "2"
		)
		(pin "11"
		)
		(pin "21"
		)
		(pin "1"
		)
		(pin "12"
		)
		(pin "22"
		)
		(pin "10"
		)
		(pin "13"
		)
		(pin "15"
		)
		(pin "14"
		)
		(instances
			(project "polarfire-som"
				(path ""
					(reference "U7")
					(unit 1)
				)
			)
		)
	)
	(symbol
		(lib_id "antmicropower:GND")
		(at 200.66 76.2 0)
		(unit 1)
		(exclude_from_sim no)
		(in_bom yes)
		(on_board yes)
		(dnp no)
		(fields_autoplaced yes)
		(property "Reference" "#PWR093"
			(at 209.55 78.74 0)
			(effects
				(font
					(size 1.27 1.27)
					(thickness 0.15)
				)
				(justify left bottom)
				(hide yes)
			)
		)
		(property "Value" "GND"
			(at 200.66 81.28 0)
			(effects
				(font
					(size 1.27 1.27)
					(thickness 0.15)
				)
			)
		)
		(property "Footprint" ""
			(at 209.55 83.82 0)
			(effects
				(font
					(size 1.27 1.27)
					(thickness 0.15)
				)
				(justify left bottom)
				(hide yes)
			)
		)
		(property "Datasheet" ""
			(at 209.55 88.9 0)
			(effects
				(font
					(size 1.27 1.27)
					(thickness 0.15)
				)
				(justify left bottom)
				(hide yes)
			)
		)
		(property "Description" ""
			(at 200.66 76.2 0)
			(effects
				(font
					(size 1.27 1.27)
				)
				(hide yes)
			)
		)
		(property "Author" "Antmicro"
			(at 209.55 83.82 0)
			(effects
				(font
					(size 1.27 1.27)
					(thickness 0.15)
				)
				(justify left bottom)
				(hide yes)
			)
		)
		(property "License" "Apache-2.0"
			(at 209.55 86.36 0)
			(effects
				(font
					(size 1.27 1.27)
					(thickness 0.15)
				)
				(justify left bottom)
				(hide yes)
			)
		)
		(pin "1"
		)
		(instances
			(project "polarfire-som"
				(path ""
					(reference "#PWR093")
					(unit 1)
				)
			)
		)
	)
	(symbol
		(lib_id "antmicropower:GND")
		(at 281.94 231.14 0)
		(unit 1)
		(exclude_from_sim no)
		(in_bom yes)
		(on_board yes)
		(dnp no)
		(fields_autoplaced yes)
		(property "Reference" "#PWR0108"
			(at 281.94 237.49 0)
			(effects
				(font
					(size 1.27 1.27)
				)
				(hide yes)
			)
		)
		(property "Value" "GND"
			(at 281.94 236.22 0)
			(effects
				(font
					(size 1.27 1.27)
					(thickness 0.15)
				)
			)
		)
		(property "Footprint" ""
			(at 290.83 238.76 0)
			(effects
				(font
					(size 1.27 1.27)
					(thickness 0.15)
				)
				(justify left bottom)
				(hide yes)
			)
		)
		(property "Datasheet" ""
			(at 290.83 243.84 0)
			(effects
				(font
					(size 1.27 1.27)
					(thickness 0.15)
				)
				(justify left bottom)
				(hide yes)
			)
		)
		(property "Description" ""
			(at 281.94 231.14 0)
			(effects
				(font
					(size 1.27 1.27)
				)
				(hide yes)
			)
		)
		(property "Author" "Antmicro"
			(at 290.83 238.76 0)
			(effects
				(font
					(size 1.27 1.27)
					(thickness 0.15)
				)
				(justify left bottom)
				(hide yes)
			)
		)
		(property "License" "Apache-2.0"
			(at 290.83 241.3 0)
			(effects
				(font
					(size 1.27 1.27)
					(thickness 0.15)
				)
				(justify left bottom)
				(hide yes)
			)
		)
		(pin "1"
		)
		(instances
			(project "polarfire-som"
				(path ""
					(reference "#PWR0108")
					(unit 1)
				)
			)
		)
	)
	(symbol
		(lib_id "antmicroCapacitors0402:C_22u_0402")
		(at 261.62 99.06 90)
		(unit 1)
		(exclude_from_sim no)
		(in_bom yes)
		(on_board yes)
		(dnp no)
		(fields_autoplaced yes)
		(property "Reference" "C102"
			(at 264.16 95.2436 90)
			(effects
				(font
					(size 1.27 1.27)
					(thickness 0.15)
				)
				(justify right)
			)
		)
		(property "Value" "C_22u_0402"
			(at 271.78 78.74 0)
			(effects
				(font
					(size 1.27 1.27)
					(thickness 0.15)
				)
				(justify left bottom)
				(hide yes)
			)
		)
		(property "Footprint" "antmicro-footprints:C_0402_1005Metric"
			(at 274.32 78.74 0)
			(effects
				(font
					(size 1.27 1.27)
					(thickness 0.15)
				)
				(justify left bottom)
				(hide yes)
			)
		)
		(property "Datasheet" "https://www.murata.com/products/productdetail?partno=GRM158R60J226ME01%23"
			(at 276.86 78.74 0)
			(effects
				(font
					(size 1.27 1.27)
					(thickness 0.15)
				)
				(justify left bottom)
				(hide yes)
			)
		)
		(property "Description" "SMD Multilayer Ceramic Capacitor, 22 uF, 4 V, 0402 [1005 Metric], X6S"
			(at 261.62 99.06 0)
			(effects
				(font
					(size 1.27 1.27)
				)
				(hide yes)
			)
		)
		(property "MPN" "GRM158R60J226ME01D"
			(at 279.4 78.74 0)
			(effects
				(font
					(size 1.27 1.27)
					(thickness 0.15)
				)
				(justify left bottom)
				(hide yes)
			)
		)
		(property "Manufacturer" "Murata"
			(at 281.94 78.74 0)
			(effects
				(font
					(size 1.27 1.27)
					(thickness 0.15)
				)
				(justify left bottom)
				(hide yes)
			)
		)
		(property "License" "Apache-2.0"
			(at 284.48 78.74 0)
			(effects
				(font
					(size 1.27 1.27)
					(thickness 0.15)
				)
				(justify left bottom)
				(hide yes)
			)
		)
		(property "Author" "Antmicro"
			(at 287.02 78.74 0)
			(effects
				(font
					(size 1.27 1.27)
					(thickness 0.15)
				)
				(justify left bottom)
				(hide yes)
			)
		)
		(property "Val" "22u"
			(at 264.16 97.7836 90)
			(effects
				(font
					(size 1.27 1.27)
					(thickness 0.15)
				)
				(justify right)
			)
		)
		(property "Voltage" ""
			(at 289.56 78.74 0)
			(effects
				(font
					(size 1.27 1.27)
				)
				(justify left bottom)
				(hide yes)
			)
		)
		(property "Dielectric" ""
			(at 292.1 78.74 0)
			(effects
				(font
					(size 1.27 1.27)
				)
				(justify left bottom)
				(hide yes)
			)
		)
		(property "Public" ""
			(at 294.64 78.74 0)
			(effects
				(font
					(size 1.27 1.27)
				)
				(justify left bottom)
				(hide yes)
			)
		)
		(pin "2"
		)
		(pin "1"
		)
		(instances
			(project "polarfire-som"
				(path ""
					(reference "C102")
					(unit 1)
				)
			)
		)
	)
	(symbol
		(lib_id "antmicropower:GND")
		(at 290.83 250.19 0)
		(unit 1)
		(exclude_from_sim no)
		(in_bom yes)
		(on_board yes)
		(dnp no)
		(fields_autoplaced yes)
		(property "Reference" "#PWR0109"
			(at 290.83 256.54 0)
			(effects
				(font
					(size 1.27 1.27)
				)
				(hide yes)
			)
		)
		(property "Value" "GND"
			(at 290.83 255.27 0)
			(effects
				(font
					(size 1.27 1.27)
					(thickness 0.15)
				)
			)
		)
		(property "Footprint" ""
			(at 299.72 257.81 0)
			(effects
				(font
					(size 1.27 1.27)
					(thickness 0.15)
				)
				(justify left bottom)
				(hide yes)
			)
		)
		(property "Datasheet" ""
			(at 299.72 262.89 0)
			(effects
				(font
					(size 1.27 1.27)
					(thickness 0.15)
				)
				(justify left bottom)
				(hide yes)
			)
		)
		(property "Description" ""
			(at 290.83 250.19 0)
			(effects
				(font
					(size 1.27 1.27)
				)
				(hide yes)
			)
		)
		(property "Author" "Antmicro"
			(at 299.72 257.81 0)
			(effects
				(font
					(size 1.27 1.27)
					(thickness 0.15)
				)
				(justify left bottom)
				(hide yes)
			)
		)
		(property "License" "Apache-2.0"
			(at 299.72 260.35 0)
			(effects
				(font
					(size 1.27 1.27)
					(thickness 0.15)
				)
				(justify left bottom)
				(hide yes)
			)
		)
		(pin "1"
		)
		(instances
			(project "polarfire-som"
				(path ""
					(reference "#PWR0109")
					(unit 1)
				)
			)
		)
	)
	(symbol
		(lib_id "antmicroResistors0402:R_4R7_0402")
		(at 187.96 92.71 0)
		(unit 1)
		(exclude_from_sim no)
		(in_bom yes)
		(on_board yes)
		(dnp no)
		(property "Reference" "R11"
			(at 190.5 90.17 0)
			(effects
				(font
					(size 1.27 1.27)
					(thickness 0.15)
				)
			)
		)
		(property "Value" "R_4R7_0402"
			(at 208.28 105.41 0)
			(effects
				(font
					(size 1.27 1.27)
					(thickness 0.15)
				)
				(justify left bottom)
				(hide yes)
			)
		)
		(property "Footprint" "antmicro-footprints:R_0402_1005Metric"
			(at 208.28 107.95 0)
			(effects
				(font
					(size 1.27 1.27)
					(thickness 0.15)
				)
				(justify left bottom)
				(hide yes)
			)
		)
		(property "Datasheet" "https://www.bourns.com/docs/product-datasheets/cr.pdf"
			(at 208.28 110.49 0)
			(effects
				(font
					(size 1.27 1.27)
					(thickness 0.15)
				)
				(justify left bottom)
				(hide yes)
			)
		)
		(property "Description" "SMD Chip Resistor, 4.7 ohm, ± 1%, 62.5 mW, 0402 [1005 Metric], Thick Film, General Purpose"
			(at 187.96 92.71 0)
			(effects
				(font
					(size 1.27 1.27)
				)
				(hide yes)
			)
		)
		(property "MPN" "CR0402-FX-4R70GLF"
			(at 208.28 113.03 0)
			(effects
				(font
					(size 1.27 1.27)
					(thickness 0.15)
				)
				(justify left bottom)
				(hide yes)
			)
		)
		(property "Manufacturer" "Bourns"
			(at 208.28 115.57 0)
			(effects
				(font
					(size 1.27 1.27)
					(thickness 0.15)
				)
				(justify left bottom)
				(hide yes)
			)
		)
		(property "License" "Apache-2.0"
			(at 208.28 118.11 0)
			(effects
				(font
					(size 1.27 1.27)
					(thickness 0.15)
				)
				(justify left bottom)
				(hide yes)
			)
		)
		(property "Author" "Antmicro"
			(at 208.28 120.65 0)
			(effects
				(font
					(size 1.27 1.27)
					(thickness 0.15)
				)
				(justify left bottom)
				(hide yes)
			)
		)
		(property "Val" "4R7"
			(at 190.5 95.25 0)
			(effects
				(font
					(size 1.27 1.27)
					(thickness 0.15)
				)
			)
		)
		(property "Tolerance" "1%"
			(at 208.28 102.87 0)
			(effects
				(font
					(size 1.27 1.27)
				)
				(justify left bottom)
				(hide yes)
			)
		)
		(property "Public" ""
			(at 208.28 123.19 0)
			(effects
				(font
					(size 1.27 1.27)
				)
				(justify left bottom)
				(hide yes)
			)
		)
		(pin "1"
		)
		(pin "2"
		)
		(instances
			(project "polarfire-som"
				(path ""
					(reference "R11")
					(unit 1)
				)
			)
		)
	)
	(symbol
		(lib_id "antmicropower:GND")
		(at 217.17 243.84 0)
		(unit 1)
		(exclude_from_sim no)
		(in_bom yes)
		(on_board yes)
		(dnp no)
		(property "Reference" "#PWR095"
			(at 226.06 246.38 0)
			(effects
				(font
					(size 1.27 1.27)
					(thickness 0.15)
				)
				(justify left bottom)
				(hide yes)
			)
		)
		(property "Value" "GND"
			(at 217.17 247.65 0)
			(effects
				(font
					(size 1.27 1.27)
					(thickness 0.15)
				)
			)
		)
		(property "Footprint" ""
			(at 226.06 251.46 0)
			(effects
				(font
					(size 1.27 1.27)
					(thickness 0.15)
				)
				(justify left bottom)
				(hide yes)
			)
		)
		(property "Datasheet" ""
			(at 226.06 256.54 0)
			(effects
				(font
					(size 1.27 1.27)
					(thickness 0.15)
				)
				(justify left bottom)
				(hide yes)
			)
		)
		(property "Description" ""
			(at 217.17 243.84 0)
			(effects
				(font
					(size 1.27 1.27)
				)
				(hide yes)
			)
		)
		(property "Author" "Antmicro"
			(at 226.06 251.46 0)
			(effects
				(font
					(size 1.27 1.27)
					(thickness 0.15)
				)
				(justify left bottom)
				(hide yes)
			)
		)
		(property "License" "Apache-2.0"
			(at 226.06 254 0)
			(effects
				(font
					(size 1.27 1.27)
					(thickness 0.15)
				)
				(justify left bottom)
				(hide yes)
			)
		)
		(pin "1"
		)
		(instances
			(project "polarfire-som"
				(path ""
					(reference "#PWR095")
					(unit 1)
				)
			)
		)
	)
	(symbol
		(lib_id "antmicroResistors0402:R_49k9_0402")
		(at 63.5 133.35 270)
		(mirror x)
		(unit 1)
		(exclude_from_sim no)
		(in_bom yes)
		(on_board yes)
		(dnp no)
		(property "Reference" "R5"
			(at 61.595 129.5399 90)
			(effects
				(font
					(size 1.27 1.27)
					(thickness 0.15)
				)
				(justify right)
			)
		)
		(property "Value" "R_49k9_0402"
			(at 50.8 113.03 0)
			(effects
				(font
					(size 1.27 1.27)
					(thickness 0.15)
				)
				(justify left bottom)
				(hide yes)
			)
		)
		(property "Footprint" "antmicro-footprints:R_0402_1005Metric"
			(at 48.26 113.03 0)
			(effects
				(font
					(size 1.27 1.27)
					(thickness 0.15)
				)
				(justify left bottom)
				(hide yes)
			)
		)
		(property "Datasheet" "https://www.bourns.com/docs/product-datasheets/cr.pdf"
			(at 45.72 113.03 0)
			(effects
				(font
					(size 1.27 1.27)
					(thickness 0.15)
				)
				(justify left bottom)
				(hide yes)
			)
		)
		(property "Description" "SMD Chip Resistor, 49.9 kohm, ± 1%, 63 mW, 0402 [1005 Metric], Thick Film, General Purpose"
			(at 63.5 133.35 0)
			(effects
				(font
					(size 1.27 1.27)
				)
				(hide yes)
			)
		)
		(property "MPN" "CR0402-FX-4992GLF"
			(at 43.18 113.03 0)
			(effects
				(font
					(size 1.27 1.27)
					(thickness 0.15)
				)
				(justify left bottom)
				(hide yes)
			)
		)
		(property "Manufacturer" "Bourns"
			(at 40.64 113.03 0)
			(effects
				(font
					(size 1.27 1.27)
					(thickness 0.15)
				)
				(justify left bottom)
				(hide yes)
			)
		)
		(property "License" "Apache-2.0"
			(at 38.1 113.03 0)
			(effects
				(font
					(size 1.27 1.27)
					(thickness 0.15)
				)
				(justify left bottom)
				(hide yes)
			)
		)
		(property "Author" "Antmicro"
			(at 35.56 113.03 0)
			(effects
				(font
					(size 1.27 1.27)
					(thickness 0.15)
				)
				(justify left bottom)
				(hide yes)
			)
		)
		(property "Val" "49k9"
			(at 61.595 132.0799 90)
			(effects
				(font
					(size 1.27 1.27)
					(thickness 0.15)
				)
				(justify right)
			)
		)
		(property "Tolerance" "1%"
			(at 53.34 113.03 0)
			(effects
				(font
					(size 1.27 1.27)
				)
				(justify left bottom)
				(hide yes)
			)
		)
		(property "Public" ""
			(at 33.02 113.03 0)
			(effects
				(font
					(size 1.27 1.27)
				)
				(justify left bottom)
				(hide yes)
			)
		)
		(pin "1"
		)
		(pin "2"
		)
		(instances
			(project "polarfire-som"
				(path ""
					(reference "R5")
					(unit 1)
				)
			)
		)
	)
	(symbol
		(lib_id "antmicroResistors0402:R_0R_0402")
		(at 88.9 242.57 90)
		(unit 1)
		(exclude_from_sim no)
		(in_bom yes)
		(on_board yes)
		(dnp no)
		(fields_autoplaced yes)
		(property "Reference" "R9"
			(at 90.805 238.7599 90)
			(effects
				(font
					(size 1.27 1.27)
					(thickness 0.15)
				)
				(justify right)
			)
		)
		(property "Value" "R_0R_0402"
			(at 101.6 222.25 0)
			(effects
				(font
					(size 1.27 1.27)
					(thickness 0.15)
				)
				(justify left bottom)
				(hide yes)
			)
		)
		(property "Footprint" "antmicro-footprints:R_0402_1005Metric"
			(at 104.14 222.25 0)
			(effects
				(font
					(size 1.27 1.27)
					(thickness 0.15)
				)
				(justify left bottom)
				(hide yes)
			)
		)
		(property "Datasheet" "https://industrial.panasonic.com/cdbs/www-data/pdf/RDA0000/AOA0000C301.pdf"
			(at 106.68 222.25 0)
			(effects
				(font
					(size 1.27 1.27)
					(thickness 0.15)
				)
				(justify left bottom)
				(hide yes)
			)
		)
		(property "Description" "SMD Chip Resistor, Jumper, 0 ohm, 100 mW, 0402 [1005 Metric], Thick Film, General Purpose"
			(at 88.9 242.57 0)
			(effects
				(font
					(size 1.27 1.27)
				)
				(hide yes)
			)
		)
		(property "MPN" "ERJ2GE0R00X"
			(at 109.22 222.25 0)
			(effects
				(font
					(size 1.27 1.27)
					(thickness 0.15)
				)
				(justify left bottom)
				(hide yes)
			)
		)
		(property "Manufacturer" "Panasonic"
			(at 111.76 222.25 0)
			(effects
				(font
					(size 1.27 1.27)
					(thickness 0.15)
				)
				(justify left bottom)
				(hide yes)
			)
		)
		(property "License" "Apache-2.0"
			(at 114.3 222.25 0)
			(effects
				(font
					(size 1.27 1.27)
					(thickness 0.15)
				)
				(justify left bottom)
				(hide yes)
			)
		)
		(property "Author" "Antmicro"
			(at 116.84 222.25 0)
			(effects
				(font
					(size 1.27 1.27)
					(thickness 0.15)
				)
				(justify left bottom)
				(hide yes)
			)
		)
		(property "Val" "0R"
			(at 90.805 241.2999 90)
			(effects
				(font
					(size 1.27 1.27)
					(thickness 0.15)
				)
				(justify right)
			)
		)
		(property "Tolerance" "~"
			(at 99.06 222.25 0)
			(effects
				(font
					(size 1.27 1.27)
				)
				(justify left bottom)
				(hide yes)
			)
		)
		(property "Current" "1A"
			(at 119.38 222.25 0)
			(effects
				(font
					(size 1.27 1.27)
					(thickness 0.15)
				)
				(justify left bottom)
				(hide yes)
			)
		)
		(property "Public" ""
			(at 119.38 222.25 0)
			(effects
				(font
					(size 1.27 1.27)
				)
				(justify left bottom)
				(hide yes)
			)
		)
		(pin "1"
		)
		(pin "2"
		)
		(instances
			(project "polarfire-som"
				(path ""
					(reference "R9")
					(unit 1)
				)
			)
		)
	)
	(symbol
		(lib_id "antmicropower:PWR_FLAG")
		(at 217.17 207.01 0)
		(unit 1)
		(exclude_from_sim no)
		(in_bom yes)
		(on_board yes)
		(dnp no)
		(property "Reference" "#FLG02"
			(at 217.17 205.105 0)
			(effects
				(font
					(size 1.27 1.27)
				)
				(hide yes)
			)
		)
		(property "Value" "PWR_FLAG"
			(at 217.17 199.39 90)
			(effects
				(font
					(size 1.27 1.27)
				)
			)
		)
		(property "Footprint" ""
			(at 217.17 207.01 0)
			(effects
				(font
					(size 1.27 1.27)
				)
				(hide yes)
			)
		)
		(property "Datasheet" ""
			(at 217.17 207.01 0)
			(effects
				(font
					(size 1.27 1.27)
				)
				(hide yes)
			)
		)
		(property "Description" ""
			(at 217.17 207.01 0)
			(effects
				(font
					(size 1.27 1.27)
				)
				(hide yes)
			)
		)
		(pin "1"
		)
		(instances
			(project "polarfire-som"
				(path ""
					(reference "#FLG02")
					(unit 1)
				)
			)
		)
	)
	(symbol
		(lib_id "antmicropower:GND")
		(at 271.78 68.58 0)
		(unit 1)
		(exclude_from_sim no)
		(in_bom yes)
		(on_board yes)
		(dnp no)
		(property "Reference" "#PWR0105"
			(at 280.67 71.12 0)
			(effects
				(font
					(size 1.27 1.27)
					(thickness 0.15)
				)
				(justify left bottom)
				(hide yes)
			)
		)
		(property "Value" "GND"
			(at 271.78 72.39 0)
			(effects
				(font
					(size 1.27 1.27)
					(thickness 0.15)
				)
			)
		)
		(property "Footprint" ""
			(at 280.67 76.2 0)
			(effects
				(font
					(size 1.27 1.27)
					(thickness 0.15)
				)
				(justify left bottom)
				(hide yes)
			)
		)
		(property "Datasheet" ""
			(at 280.67 81.28 0)
			(effects
				(font
					(size 1.27 1.27)
					(thickness 0.15)
				)
				(justify left bottom)
				(hide yes)
			)
		)
		(property "Description" ""
			(at 271.78 68.58 0)
			(effects
				(font
					(size 1.27 1.27)
				)
				(hide yes)
			)
		)
		(property "Author" "Antmicro"
			(at 280.67 76.2 0)
			(effects
				(font
					(size 1.27 1.27)
					(thickness 0.15)
				)
				(justify left bottom)
				(hide yes)
			)
		)
		(property "License" "Apache-2.0"
			(at 280.67 78.74 0)
			(effects
				(font
					(size 1.27 1.27)
					(thickness 0.15)
				)
				(justify left bottom)
				(hide yes)
			)
		)
		(pin "1"
		)
		(instances
			(project "polarfire-som"
				(path ""
					(reference "#PWR0105")
					(unit 1)
				)
			)
		)
	)
	(symbol
		(lib_id "antmicroCapacitors0402:C_22u_0402")
		(at 261.62 67.31 90)
		(unit 1)
		(exclude_from_sim no)
		(in_bom yes)
		(on_board yes)
		(dnp no)
		(fields_autoplaced yes)
		(property "Reference" "C100"
			(at 264.16 63.4936 90)
			(effects
				(font
					(size 1.27 1.27)
					(thickness 0.15)
				)
				(justify right)
			)
		)
		(property "Value" "C_22u_0402"
			(at 271.78 46.99 0)
			(effects
				(font
					(size 1.27 1.27)
					(thickness 0.15)
				)
				(justify left bottom)
				(hide yes)
			)
		)
		(property "Footprint" "antmicro-footprints:C_0402_1005Metric"
			(at 274.32 46.99 0)
			(effects
				(font
					(size 1.27 1.27)
					(thickness 0.15)
				)
				(justify left bottom)
				(hide yes)
			)
		)
		(property "Datasheet" "https://www.murata.com/products/productdetail?partno=GRM158R60J226ME01%23"
			(at 276.86 46.99 0)
			(effects
				(font
					(size 1.27 1.27)
					(thickness 0.15)
				)
				(justify left bottom)
				(hide yes)
			)
		)
		(property "Description" "SMD Multilayer Ceramic Capacitor, 22 uF, 4 V, 0402 [1005 Metric], X6S"
			(at 261.62 67.31 0)
			(effects
				(font
					(size 1.27 1.27)
				)
				(hide yes)
			)
		)
		(property "MPN" "GRM158R60J226ME01D"
			(at 279.4 46.99 0)
			(effects
				(font
					(size 1.27 1.27)
					(thickness 0.15)
				)
				(justify left bottom)
				(hide yes)
			)
		)
		(property "Manufacturer" "Murata"
			(at 281.94 46.99 0)
			(effects
				(font
					(size 1.27 1.27)
					(thickness 0.15)
				)
				(justify left bottom)
				(hide yes)
			)
		)
		(property "License" "Apache-2.0"
			(at 284.48 46.99 0)
			(effects
				(font
					(size 1.27 1.27)
					(thickness 0.15)
				)
				(justify left bottom)
				(hide yes)
			)
		)
		(property "Author" "Antmicro"
			(at 287.02 46.99 0)
			(effects
				(font
					(size 1.27 1.27)
					(thickness 0.15)
				)
				(justify left bottom)
				(hide yes)
			)
		)
		(property "Val" "22u"
			(at 264.16 66.0336 90)
			(effects
				(font
					(size 1.27 1.27)
					(thickness 0.15)
				)
				(justify right)
			)
		)
		(property "Voltage" ""
			(at 289.56 46.99 0)
			(effects
				(font
					(size 1.27 1.27)
				)
				(justify left bottom)
				(hide yes)
			)
		)
		(property "Dielectric" ""
			(at 292.1 46.99 0)
			(effects
				(font
					(size 1.27 1.27)
				)
				(justify left bottom)
				(hide yes)
			)
		)
		(property "Public" ""
			(at 294.64 46.99 0)
			(effects
				(font
					(size 1.27 1.27)
				)
				(justify left bottom)
				(hide yes)
			)
		)
		(pin "2"
		)
		(pin "1"
		)
		(instances
			(project "polarfire-som"
				(path ""
					(reference "C100")
					(unit 1)
				)
			)
		)
	)
	(symbol
		(lib_id "antmicropower:GND")
		(at 231.14 250.19 0)
		(unit 1)
		(exclude_from_sim no)
		(in_bom yes)
		(on_board yes)
		(dnp no)
		(property "Reference" "#PWR096"
			(at 240.03 252.73 0)
			(effects
				(font
					(size 1.27 1.27)
					(thickness 0.15)
				)
				(justify left bottom)
				(hide yes)
			)
		)
		(property "Value" "GND"
			(at 231.14 254 0)
			(effects
				(font
					(size 1.27 1.27)
					(thickness 0.15)
				)
			)
		)
		(property "Footprint" ""
			(at 240.03 257.81 0)
			(effects
				(font
					(size 1.27 1.27)
					(thickness 0.15)
				)
				(justify left bottom)
				(hide yes)
			)
		)
		(property "Datasheet" ""
			(at 240.03 262.89 0)
			(effects
				(font
					(size 1.27 1.27)
					(thickness 0.15)
				)
				(justify left bottom)
				(hide yes)
			)
		)
		(property "Description" ""
			(at 231.14 250.19 0)
			(effects
				(font
					(size 1.27 1.27)
				)
				(hide yes)
			)
		)
		(property "Author" "Antmicro"
			(at 240.03 257.81 0)
			(effects
				(font
					(size 1.27 1.27)
					(thickness 0.15)
				)
				(justify left bottom)
				(hide yes)
			)
		)
		(property "License" "Apache-2.0"
			(at 240.03 260.35 0)
			(effects
				(font
					(size 1.27 1.27)
					(thickness 0.15)
				)
				(justify left bottom)
				(hide yes)
			)
		)
		(pin "1"
		)
		(instances
			(project "polarfire-som"
				(path ""
					(reference "#PWR096")
					(unit 1)
				)
			)
		)
	)
	(symbol
		(lib_id "antmicroCapacitors0402:C_22u_0402")
		(at 281.94 227.33 90)
		(unit 1)
		(exclude_from_sim no)
		(in_bom yes)
		(on_board yes)
		(dnp no)
		(property "Reference" "C110"
			(at 282.575 222.885 90)
			(effects
				(font
					(size 1.27 1.27)
					(thickness 0.15)
				)
				(justify right)
			)
		)
		(property "Value" "C_22u_0402"
			(at 292.1 207.01 0)
			(effects
				(font
					(size 1.27 1.27)
					(thickness 0.15)
				)
				(justify left bottom)
				(hide yes)
			)
		)
		(property "Footprint" "antmicro-footprints:C_0402_1005Metric"
			(at 294.64 207.01 0)
			(effects
				(font
					(size 1.27 1.27)
					(thickness 0.15)
				)
				(justify left bottom)
				(hide yes)
			)
		)
		(property "Datasheet" "https://www.murata.com/products/productdetail?partno=GRM158R60J226ME01%23"
			(at 297.18 207.01 0)
			(effects
				(font
					(size 1.27 1.27)
					(thickness 0.15)
				)
				(justify left bottom)
				(hide yes)
			)
		)
		(property "Description" "SMD Multilayer Ceramic Capacitor, 22 uF, 4 V, 0402 [1005 Metric], X6S"
			(at 281.94 227.33 0)
			(effects
				(font
					(size 1.27 1.27)
				)
				(hide yes)
			)
		)
		(property "MPN" "GRM158R60J226ME01D"
			(at 299.72 207.01 0)
			(effects
				(font
					(size 1.27 1.27)
					(thickness 0.15)
				)
				(justify left bottom)
				(hide yes)
			)
		)
		(property "Manufacturer" "Murata"
			(at 302.26 207.01 0)
			(effects
				(font
					(size 1.27 1.27)
					(thickness 0.15)
				)
				(justify left bottom)
				(hide yes)
			)
		)
		(property "License" "Apache-2.0"
			(at 304.8 207.01 0)
			(effects
				(font
					(size 1.27 1.27)
					(thickness 0.15)
				)
				(justify left bottom)
				(hide yes)
			)
		)
		(property "Author" "Antmicro"
			(at 307.34 207.01 0)
			(effects
				(font
					(size 1.27 1.27)
					(thickness 0.15)
				)
				(justify left bottom)
				(hide yes)
			)
		)
		(property "Val" "22u"
			(at 282.575 226.695 90)
			(effects
				(font
					(size 1.27 1.27)
					(thickness 0.15)
				)
				(justify right)
			)
		)
		(property "Voltage" ""
			(at 309.88 207.01 0)
			(effects
				(font
					(size 1.27 1.27)
				)
				(justify left bottom)
				(hide yes)
			)
		)
		(property "Dielectric" ""
			(at 312.42 207.01 0)
			(effects
				(font
					(size 1.27 1.27)
				)
				(justify left bottom)
				(hide yes)
			)
		)
		(property "Public" ""
			(at 314.96 207.01 0)
			(effects
				(font
					(size 1.27 1.27)
				)
				(justify left bottom)
				(hide yes)
			)
		)
		(pin "2"
		)
		(pin "1"
		)
		(instances
			(project "polarfire-som"
				(path ""
					(reference "C110")
					(unit 1)
				)
			)
		)
	)
	(symbol
		(lib_id "antmicropower:+1V8")
		(at 299.72 91.44 0)
		(unit 1)
		(exclude_from_sim no)
		(in_bom yes)
		(on_board yes)
		(dnp no)
		(fields_autoplaced yes)
		(property "Reference" "#PWR0183"
			(at 314.96 93.98 0)
			(effects
				(font
					(size 1.27 1.27)
					(thickness 0.15)
				)
				(justify left bottom)
				(hide yes)
			)
		)
		(property "Value" "+1V8"
			(at 299.72 86.36 0)
			(effects
				(font
					(size 1.27 1.27)
					(thickness 0.15)
				)
			)
		)
		(property "Footprint" ""
			(at 314.96 99.06 0)
			(effects
				(font
					(size 1.27 1.27)
					(thickness 0.15)
				)
				(justify left bottom)
				(hide yes)
			)
		)
		(property "Datasheet" ""
			(at 314.96 101.6 0)
			(effects
				(font
					(size 1.27 1.27)
					(thickness 0.15)
				)
				(justify left bottom)
				(hide yes)
			)
		)
		(property "Description" ""
			(at 299.72 91.44 0)
			(effects
				(font
					(size 1.27 1.27)
				)
				(hide yes)
			)
		)
		(property "Author" "Antmicro"
			(at 314.96 96.52 0)
			(effects
				(font
					(size 1.27 1.27)
					(thickness 0.15)
				)
				(justify left bottom)
				(hide yes)
			)
		)
		(property "License" "Apache-2.0"
			(at 314.96 99.06 0)
			(effects
				(font
					(size 1.27 1.27)
					(thickness 0.15)
				)
				(justify left bottom)
				(hide yes)
			)
		)
		(pin "1"
		)
		(instances
			(project "polarfire-som"
				(path ""
					(reference "#PWR0183")
					(unit 1)
				)
			)
		)
	)
	(symbol
		(lib_id "antmicroFixedInductors:L_1u5_7.5A_Coilcraft-XEL4020")
		(at 247.65 219.71 0)
		(unit 1)
		(exclude_from_sim no)
		(in_bom yes)
		(on_board yes)
		(dnp no)
		(fields_autoplaced yes)
		(property "Reference" "L1"
			(at 250.19 213.995 0)
			(effects
				(font
					(size 1.27 1.27)
					(thickness 0.15)
				)
			)
		)
		(property "Value" "L_1u5_7.5A_Coilcraft-XEL4020"
			(at 261.62 222.25 0)
			(effects
				(font
					(size 1.27 1.27)
					(thickness 0.15)
				)
				(justify left bottom)
				(hide yes)
			)
		)
		(property "Footprint" "antmicro-footprints:L_Coilcraft-XEL4020"
			(at 261.62 227.33 0)
			(effects
				(font
					(size 1.27 1.27)
					(thickness 0.15)
				)
				(justify left bottom)
				(hide yes)
			)
		)
		(property "Datasheet" "https://www.coilcraft.com/getmedia/3c7caaa2-c1ed-4ff8-84e5-0b1b14a30417/xel4020.pdf"
			(at 261.62 229.87 0)
			(effects
				(font
					(size 1.27 1.27)
					(thickness 0.15)
				)
				(justify left bottom)
				(hide yes)
			)
		)
		(property "Description" "Power Inductor (SMT), 1.5 µH, 7.5 A, Shielded, 7.4 A, XEL4020-152MEC"
			(at 247.65 219.71 0)
			(effects
				(font
					(size 1.27 1.27)
				)
				(hide yes)
			)
		)
		(property "Val" "1u5/7.5A"
			(at 250.19 216.535 0)
			(effects
				(font
					(size 1.27 1.27)
					(thickness 0.15)
				)
			)
		)
		(property "Manufacturer" "Coilcraft"
			(at 261.62 232.41 0)
			(effects
				(font
					(size 1.27 1.27)
					(thickness 0.15)
				)
				(justify left bottom)
				(hide yes)
			)
		)
		(property "MPN" "XEL4020-152MEC "
			(at 261.62 234.95 0)
			(effects
				(font
					(size 1.27 1.27)
					(thickness 0.15)
				)
				(justify left bottom)
				(hide yes)
			)
		)
		(property "ISat" "7.4 A"
			(at 261.62 236.22 0)
			(effects
				(font
					(size 1.27 1.27)
				)
				(justify left)
				(hide yes)
			)
		)
		(property "IMax" "7.5 A"
			(at 261.62 240.03 0)
			(effects
				(font
					(size 1.27 1.27)
					(thickness 0.15)
				)
				(justify left bottom)
				(hide yes)
			)
		)
		(property "Size" "4x4"
			(at 261.62 242.57 0)
			(effects
				(font
					(size 1.27 1.27)
					(thickness 0.15)
				)
				(justify left bottom)
				(hide yes)
			)
		)
		(property "Author" "Antmicro"
			(at 261.62 245.11 0)
			(effects
				(font
					(size 1.27 1.27)
					(thickness 0.15)
				)
				(justify left bottom)
				(hide yes)
			)
		)
		(property "License" "Apache-2.0"
			(at 261.62 247.65 0)
			(effects
				(font
					(size 1.27 1.27)
					(thickness 0.15)
				)
				(justify left bottom)
				(hide yes)
			)
		)
		(property "Public" ""
			(at 261.62 250.19 0)
			(effects
				(font
					(size 1.27 1.27)
				)
				(justify left bottom)
				(hide yes)
			)
		)
		(pin "1"
		)
		(pin "2"
		)
		(instances
			(project "polarfire-som"
				(path ""
					(reference "L1")
					(unit 1)
				)
			)
		)
	)
	(symbol
		(lib_id "antmicroCapacitors0402:C_22p_0402")
		(at 302.26 237.49 90)
		(unit 1)
		(exclude_from_sim no)
		(in_bom yes)
		(on_board yes)
		(dnp no)
		(fields_autoplaced yes)
		(property "Reference" "C111"
			(at 304.8 233.6736 90)
			(effects
				(font
					(size 1.27 1.27)
					(thickness 0.15)
				)
				(justify right)
			)
		)
		(property "Value" "C_22p_0402"
			(at 312.42 217.17 0)
			(effects
				(font
					(size 1.27 1.27)
					(thickness 0.15)
				)
				(justify left bottom)
				(hide yes)
			)
		)
		(property "Footprint" "antmicro-footprints:C_0402_1005Metric"
			(at 314.96 217.17 0)
			(effects
				(font
					(size 1.27 1.27)
					(thickness 0.15)
				)
				(justify left bottom)
				(hide yes)
			)
		)
		(property "Datasheet" "https://www.yageo.com/en/Chart/Download/pdf/CC0402JRNPO9BN220"
			(at 317.5 217.17 0)
			(effects
				(font
					(size 1.27 1.27)
					(thickness 0.15)
				)
				(justify left bottom)
				(hide yes)
			)
		)
		(property "Description" "SMD Multilayer Ceramic Capacitor, 22 pF, 50 V, 0402 [1005 Metric], ± 5%, C0G / NP0, CC Series"
			(at 302.26 237.49 0)
			(effects
				(font
					(size 1.27 1.27)
				)
				(hide yes)
			)
		)
		(property "MPN" "CC0402JRNPO9BN220"
			(at 320.04 217.17 0)
			(effects
				(font
					(size 1.27 1.27)
					(thickness 0.15)
				)
				(justify left bottom)
				(hide yes)
			)
		)
		(property "Manufacturer" "YAGEO"
			(at 322.58 217.17 0)
			(effects
				(font
					(size 1.27 1.27)
					(thickness 0.15)
				)
				(justify left bottom)
				(hide yes)
			)
		)
		(property "License" "Apache-2.0"
			(at 325.12 217.17 0)
			(effects
				(font
					(size 1.27 1.27)
					(thickness 0.15)
				)
				(justify left bottom)
				(hide yes)
			)
		)
		(property "Author" "Antmicro"
			(at 327.66 217.17 0)
			(effects
				(font
					(size 1.27 1.27)
					(thickness 0.15)
				)
				(justify left bottom)
				(hide yes)
			)
		)
		(property "Val" "22p"
			(at 304.8 236.2136 90)
			(effects
				(font
					(size 1.27 1.27)
					(thickness 0.15)
				)
				(justify right)
			)
		)
		(property "Voltage" ""
			(at 330.2 217.17 0)
			(effects
				(font
					(size 1.27 1.27)
				)
				(justify left bottom)
				(hide yes)
			)
		)
		(property "Dielectric" ""
			(at 332.74 217.17 0)
			(effects
				(font
					(size 1.27 1.27)
				)
				(justify left bottom)
				(hide yes)
			)
		)
		(property "Public" ""
			(at 335.28 217.17 0)
			(effects
				(font
					(size 1.27 1.27)
				)
				(justify left bottom)
				(hide yes)
			)
		)
		(pin "1"
		)
		(pin "2"
		)
		(instances
			(project "polarfire-som"
				(path ""
					(reference "C111")
					(unit 1)
				)
			)
		)
	)
	(symbol
		(lib_id "antmicropower:GND")
		(at 271.78 118.11 0)
		(unit 1)
		(exclude_from_sim no)
		(in_bom yes)
		(on_board yes)
		(dnp no)
		(fields_autoplaced yes)
		(property "Reference" "#PWR0107"
			(at 280.67 120.65 0)
			(effects
				(font
					(size 1.27 1.27)
					(thickness 0.15)
				)
				(justify left bottom)
				(hide yes)
			)
		)
		(property "Value" "GND"
			(at 271.78 123.19 0)
			(effects
				(font
					(size 1.27 1.27)
					(thickness 0.15)
				)
			)
		)
		(property "Footprint" ""
			(at 280.67 125.73 0)
			(effects
				(font
					(size 1.27 1.27)
					(thickness 0.15)
				)
				(justify left bottom)
				(hide yes)
			)
		)
		(property "Datasheet" ""
			(at 280.67 130.81 0)
			(effects
				(font
					(size 1.27 1.27)
					(thickness 0.15)
				)
				(justify left bottom)
				(hide yes)
			)
		)
		(property "Description" ""
			(at 271.78 118.11 0)
			(effects
				(font
					(size 1.27 1.27)
				)
				(hide yes)
			)
		)
		(property "Author" "Antmicro"
			(at 280.67 125.73 0)
			(effects
				(font
					(size 1.27 1.27)
					(thickness 0.15)
				)
				(justify left bottom)
				(hide yes)
			)
		)
		(property "License" "Apache-2.0"
			(at 280.67 128.27 0)
			(effects
				(font
					(size 1.27 1.27)
					(thickness 0.15)
				)
				(justify left bottom)
				(hide yes)
			)
		)
		(pin "1"
		)
		(instances
			(project "polarfire-som"
				(path ""
					(reference "#PWR0107")
					(unit 1)
				)
			)
		)
	)
	(symbol
		(lib_id "antmicroTestPoints:TP_0.75mm_SMD")
		(at 276.86 90.17 0)
		(unit 1)
		(exclude_from_sim no)
		(in_bom no)
		(on_board yes)
		(dnp no)
		(property "Reference" "TP7"
			(at 283.845 90.17 0)
			(effects
				(font
					(size 1.27 1.27)
					(thickness 0.15)
				)
			)
		)
		(property "Value" "TP_0.75mm_SMD"
			(at 287.655 93.98 0)
			(effects
				(font
					(size 1.27 1.27)
					(thickness 0.15)
				)
				(justify left bottom)
				(hide yes)
			)
		)
		(property "Footprint" "antmicro-footprints:TP_SMD_0.75mm"
			(at 287.655 96.52 0)
			(effects
				(font
					(size 1.27 1.27)
					(thickness 0.15)
				)
				(justify left bottom)
				(hide yes)
			)
		)
		(property "Datasheet" ""
			(at 294.64 102.87 0)
			(effects
				(font
					(size 1.27 1.27)
					(thickness 0.15)
				)
				(justify left bottom)
				(hide yes)
			)
		)
		(property "Description" "SMT test point"
			(at 276.86 90.17 0)
			(effects
				(font
					(size 1.27 1.27)
				)
				(hide yes)
			)
		)
		(property "MPN" ""
			(at 287.655 101.6 0)
			(effects
				(font
					(size 1.27 1.27)
					(thickness 0.15)
				)
				(justify left bottom)
				(hide yes)
			)
		)
		(property "Manufacturer" ""
			(at 287.655 96.52 0)
			(effects
				(font
					(size 1.27 1.27)
					(thickness 0.15)
				)
				(justify left bottom)
				(hide yes)
			)
		)
		(property "Author" "Antmicro"
			(at 287.655 99.06 0)
			(effects
				(font
					(size 1.27 1.27)
					(thickness 0.15)
				)
				(justify left bottom)
				(hide yes)
			)
		)
		(property "License" "Apache-2.0"
			(at 287.655 101.6 0)
			(effects
				(font
					(size 1.27 1.27)
					(thickness 0.15)
				)
				(justify left bottom)
				(hide yes)
			)
		)
		(property "Public" "False"
			(at 287.02 104.14 0)
			(effects
				(font
					(size 1.27 1.27)
				)
				(justify left bottom)
				(hide yes)
			)
		)
		(pin "1"
		)
		(instances
			(project "polarfire-som"
				(path ""
					(reference "TP7")
					(unit 1)
				)
			)
		)
	)
	(symbol
		(lib_id "antmicroTestPoints:TP_0.75mm_SMD")
		(at 157.48 146.05 0)
		(unit 1)
		(exclude_from_sim no)
		(in_bom no)
		(on_board yes)
		(dnp no)
		(property "Reference" "TP38"
			(at 164.465 146.05 0)
			(effects
				(font
					(size 1.27 1.27)
					(thickness 0.15)
				)
			)
		)
		(property "Value" "TP_0.75mm_SMD"
			(at 168.275 149.86 0)
			(effects
				(font
					(size 1.27 1.27)
					(thickness 0.15)
				)
				(justify left bottom)
				(hide yes)
			)
		)
		(property "Footprint" "antmicro-footprints:TP_SMD_0.75mm"
			(at 168.275 152.4 0)
			(effects
				(font
					(size 1.27 1.27)
					(thickness 0.15)
				)
				(justify left bottom)
				(hide yes)
			)
		)
		(property "Datasheet" ""
			(at 175.26 158.75 0)
			(effects
				(font
					(size 1.27 1.27)
					(thickness 0.15)
				)
				(justify left bottom)
				(hide yes)
			)
		)
		(property "Description" "SMT test point"
			(at 157.48 146.05 0)
			(effects
				(font
					(size 1.27 1.27)
				)
				(hide yes)
			)
		)
		(property "MPN" ""
			(at 168.275 157.48 0)
			(effects
				(font
					(size 1.27 1.27)
					(thickness 0.15)
				)
				(justify left bottom)
				(hide yes)
			)
		)
		(property "Manufacturer" ""
			(at 168.275 152.4 0)
			(effects
				(font
					(size 1.27 1.27)
					(thickness 0.15)
				)
				(justify left bottom)
				(hide yes)
			)
		)
		(property "Author" "Antmicro"
			(at 168.275 154.94 0)
			(effects
				(font
					(size 1.27 1.27)
					(thickness 0.15)
				)
				(justify left bottom)
				(hide yes)
			)
		)
		(property "License" "Apache-2.0"
			(at 168.275 157.48 0)
			(effects
				(font
					(size 1.27 1.27)
					(thickness 0.15)
				)
				(justify left bottom)
				(hide yes)
			)
		)
		(property "Public" "False"
			(at 167.64 160.02 0)
			(effects
				(font
					(size 1.27 1.27)
				)
				(justify left bottom)
				(hide yes)
			)
		)
		(pin "1"
		)
		(instances
			(project "polarfire-som"
				(path ""
					(reference "TP38")
					(unit 1)
				)
			)
		)
	)
	(symbol
		(lib_id "antmicropower:VDDI")
		(at 64.77 46.99 0)
		(unit 1)
		(exclude_from_sim no)
		(in_bom yes)
		(on_board yes)
		(dnp no)
		(fields_autoplaced yes)
		(property "Reference" "#PWR0321"
			(at 64.77 50.8 0)
			(effects
				(font
					(size 1.27 1.27)
				)
				(hide yes)
			)
		)
		(property "Value" "VDD"
			(at 64.77 42.545 0)
			(effects
				(font
					(size 1.27 1.27)
				)
			)
		)
		(property "Footprint" ""
			(at 64.77 46.99 0)
			(effects
				(font
					(size 1.27 1.27)
				)
				(hide yes)
			)
		)
		(property "Datasheet" ""
			(at 64.77 46.99 0)
			(effects
				(font
					(size 1.27 1.27)
				)
				(hide yes)
			)
		)
		(property "Description" ""
			(at 64.77 46.99 0)
			(effects
				(font
					(size 1.27 1.27)
				)
				(hide yes)
			)
		)
		(pin "1"
		)
		(instances
			(project "polarfire-som"
				(path ""
					(reference "#PWR0321")
					(unit 1)
				)
			)
		)
	)
	(symbol
		(lib_id "antmicropower:GND")
		(at 85.09 252.73 0)
		(unit 1)
		(exclude_from_sim no)
		(in_bom yes)
		(on_board yes)
		(dnp no)
		(property "Reference" "#PWR079"
			(at 93.98 255.27 0)
			(effects
				(font
					(size 1.27 1.27)
					(thickness 0.15)
				)
				(justify left bottom)
				(hide yes)
			)
		)
		(property "Value" "GND"
			(at 85.09 256.54 0)
			(effects
				(font
					(size 1.27 1.27)
					(thickness 0.15)
				)
			)
		)
		(property "Footprint" ""
			(at 93.98 260.35 0)
			(effects
				(font
					(size 1.27 1.27)
					(thickness 0.15)
				)
				(justify left bottom)
				(hide yes)
			)
		)
		(property "Datasheet" ""
			(at 93.98 265.43 0)
			(effects
				(font
					(size 1.27 1.27)
					(thickness 0.15)
				)
				(justify left bottom)
				(hide yes)
			)
		)
		(property "Description" ""
			(at 85.09 252.73 0)
			(effects
				(font
					(size 1.27 1.27)
				)
				(hide yes)
			)
		)
		(property "Author" "Antmicro"
			(at 93.98 260.35 0)
			(effects
				(font
					(size 1.27 1.27)
					(thickness 0.15)
				)
				(justify left bottom)
				(hide yes)
			)
		)
		(property "License" "Apache-2.0"
			(at 93.98 262.89 0)
			(effects
				(font
					(size 1.27 1.27)
					(thickness 0.15)
				)
				(justify left bottom)
				(hide yes)
			)
		)
		(pin "1"
		)
		(instances
			(project "polarfire-som"
				(path ""
					(reference "#PWR079")
					(unit 1)
				)
			)
		)
	)
	(symbol
		(lib_id "antmicroTestPoints:TP_0.75mm_SMD")
		(at 278.13 43.18 0)
		(unit 1)
		(exclude_from_sim no)
		(in_bom no)
		(on_board yes)
		(dnp no)
		(property "Reference" "TP4"
			(at 285.115 43.18 0)
			(effects
				(font
					(size 1.27 1.27)
					(thickness 0.15)
				)
			)
		)
		(property "Value" "TP_0.75mm_SMD"
			(at 288.925 46.99 0)
			(effects
				(font
					(size 1.27 1.27)
					(thickness 0.15)
				)
				(justify left bottom)
				(hide yes)
			)
		)
		(property "Footprint" "antmicro-footprints:TP_SMD_0.75mm"
			(at 288.925 49.53 0)
			(effects
				(font
					(size 1.27 1.27)
					(thickness 0.15)
				)
				(justify left bottom)
				(hide yes)
			)
		)
		(property "Datasheet" ""
			(at 295.91 55.88 0)
			(effects
				(font
					(size 1.27 1.27)
					(thickness 0.15)
				)
				(justify left bottom)
				(hide yes)
			)
		)
		(property "Description" "SMT test point"
			(at 278.13 43.18 0)
			(effects
				(font
					(size 1.27 1.27)
				)
				(hide yes)
			)
		)
		(property "MPN" ""
			(at 288.925 54.61 0)
			(effects
				(font
					(size 1.27 1.27)
					(thickness 0.15)
				)
				(justify left bottom)
				(hide yes)
			)
		)
		(property "Manufacturer" ""
			(at 288.925 49.53 0)
			(effects
				(font
					(size 1.27 1.27)
					(thickness 0.15)
				)
				(justify left bottom)
				(hide yes)
			)
		)
		(property "Author" "Antmicro"
			(at 288.925 52.07 0)
			(effects
				(font
					(size 1.27 1.27)
					(thickness 0.15)
				)
				(justify left bottom)
				(hide yes)
			)
		)
		(property "License" "Apache-2.0"
			(at 288.925 54.61 0)
			(effects
				(font
					(size 1.27 1.27)
					(thickness 0.15)
				)
				(justify left bottom)
				(hide yes)
			)
		)
		(property "Public" "False"
			(at 288.29 57.15 0)
			(effects
				(font
					(size 1.27 1.27)
				)
				(justify left bottom)
				(hide yes)
			)
		)
		(pin "1"
		)
		(instances
			(project "polarfire-som"
				(path ""
					(reference "TP4")
					(unit 1)
				)
			)
		)
	)
	(symbol
		(lib_id "antmicroCapacitors0402:C_100n_0402")
		(at 24.13 59.69 90)
		(unit 1)
		(exclude_from_sim no)
		(in_bom yes)
		(on_board yes)
		(dnp no)
		(property "Reference" "C84"
			(at 25.4 54.61 90)
			(effects
				(font
					(size 1.27 1.27)
					(thickness 0.15)
				)
				(justify right)
			)
		)
		(property "Value" "C_100n_0402"
			(at 34.29 39.37 0)
			(effects
				(font
					(size 1.27 1.27)
					(thickness 0.15)
				)
				(justify left bottom)
				(hide yes)
			)
		)
		(property "Footprint" "antmicro-footprints:C_0402_1005Metric"
			(at 36.83 39.37 0)
			(effects
				(font
					(size 1.27 1.27)
					(thickness 0.15)
				)
				(justify left bottom)
				(hide yes)
			)
		)
		(property "Datasheet" "https://www.murata.com/products/productdetail?partno=GRM155R61H104KE14%23"
			(at 39.37 39.37 0)
			(effects
				(font
					(size 1.27 1.27)
					(thickness 0.15)
				)
				(justify left bottom)
				(hide yes)
			)
		)
		(property "Description" "SMD Multilayer Ceramic Capacitor, 0.1 µF, 50 V, 0402 [1005 Metric], ± 10%, X5R, GRM Series"
			(at 24.13 59.69 0)
			(effects
				(font
					(size 1.27 1.27)
				)
				(hide yes)
			)
		)
		(property "MPN" "GRM155R61H104KE14D"
			(at 41.91 39.37 0)
			(effects
				(font
					(size 1.27 1.27)
					(thickness 0.15)
				)
				(justify left bottom)
				(hide yes)
			)
		)
		(property "Manufacturer" "Murata"
			(at 44.45 39.37 0)
			(effects
				(font
					(size 1.27 1.27)
					(thickness 0.15)
				)
				(justify left bottom)
				(hide yes)
			)
		)
		(property "License" "Apache-2.0"
			(at 46.99 39.37 0)
			(effects
				(font
					(size 1.27 1.27)
					(thickness 0.15)
				)
				(justify left bottom)
				(hide yes)
			)
		)
		(property "Author" "Antmicro"
			(at 49.53 39.37 0)
			(effects
				(font
					(size 1.27 1.27)
					(thickness 0.15)
				)
				(justify left bottom)
				(hide yes)
			)
		)
		(property "Val" "100n"
			(at 30.48 58.42 90)
			(effects
				(font
					(size 1.27 1.27)
					(thickness 0.15)
				)
				(justify left bottom)
			)
		)
		(property "Voltage" "50V"
			(at 52.07 39.37 0)
			(effects
				(font
					(size 1.27 1.27)
				)
				(justify left bottom)
				(hide yes)
			)
		)
		(property "Dielectric" "X5R"
			(at 54.61 39.37 0)
			(effects
				(font
					(size 1.27 1.27)
				)
				(justify left bottom)
				(hide yes)
			)
		)
		(property "Public" ""
			(at 57.15 39.37 0)
			(effects
				(font
					(size 1.27 1.27)
				)
				(justify left bottom)
				(hide yes)
			)
		)
		(pin "1"
		)
		(pin "2"
		)
		(instances
			(project "polarfire-som"
				(path ""
					(reference "C84")
					(unit 1)
				)
			)
		)
	)
	(symbol
		(lib_id "antmicroResistors0603:R_0R01_0603")
		(at 289.56 92.71 0)
		(unit 1)
		(exclude_from_sim no)
		(in_bom yes)
		(on_board yes)
		(dnp no)
		(fields_autoplaced yes)
		(property "Reference" "R48"
			(at 292.1 86.36 0)
			(effects
				(font
					(size 1.27 1.27)
					(thickness 0.15)
				)
			)
		)
		(property "Value" "R_0R01_0603"
			(at 309.88 105.41 0)
			(effects
				(font
					(size 1.27 1.27)
					(thickness 0.15)
				)
				(justify left bottom)
				(hide yes)
			)
		)
		(property "Footprint" "antmicro-footprints:R_0603_1608Metric"
			(at 309.88 107.95 0)
			(effects
				(font
					(size 1.27 1.27)
					(thickness 0.15)
				)
				(justify left bottom)
				(hide yes)
			)
		)
		(property "Datasheet" "https://www.bourns.com/docs/product-datasheets/cfn-a.pdf"
			(at 309.88 110.49 0)
			(effects
				(font
					(size 1.27 1.27)
					(thickness 0.15)
				)
				(justify left bottom)
				(hide yes)
			)
		)
		(property "Description" "SMD Chip Resistor, 10 mohm, ± 1%, 0.5 W, 0603 [1608 Metric], Metal Foil, Current Sensing"
			(at 289.56 92.71 0)
			(effects
				(font
					(size 1.27 1.27)
				)
				(hide yes)
			)
		)
		(property "MPN" "CFN0603AFZ-R010ELF"
			(at 309.88 113.03 0)
			(effects
				(font
					(size 1.27 1.27)
					(thickness 0.15)
				)
				(justify left bottom)
				(hide yes)
			)
		)
		(property "Manufacturer" "Bourns"
			(at 309.88 115.57 0)
			(effects
				(font
					(size 1.27 1.27)
					(thickness 0.15)
				)
				(justify left bottom)
				(hide yes)
			)
		)
		(property "License" "Apache-2.0"
			(at 309.88 118.11 0)
			(effects
				(font
					(size 1.27 1.27)
					(thickness 0.15)
				)
				(justify left bottom)
				(hide yes)
			)
		)
		(property "Author" "Antmicro"
			(at 309.88 120.65 0)
			(effects
				(font
					(size 1.27 1.27)
					(thickness 0.15)
				)
				(justify left bottom)
				(hide yes)
			)
		)
		(property "Val" "0R01"
			(at 292.1 88.9 0)
			(effects
				(font
					(size 1.27 1.27)
					(thickness 0.15)
				)
			)
		)
		(property "Tolerance" "1%"
			(at 309.88 102.87 0)
			(effects
				(font
					(size 1.27 1.27)
				)
				(justify left bottom)
				(hide yes)
			)
		)
		(property "Public" ""
			(at 309.88 123.19 0)
			(effects
				(font
					(size 1.27 1.27)
				)
				(justify left bottom)
				(hide yes)
			)
		)
		(pin "1"
		)
		(pin "2"
		)
		(instances
			(project "polarfire-som"
				(path ""
					(reference "R48")
					(unit 1)
				)
			)
		)
	)
	(symbol
		(lib_id "antmicropower:VDDAUX")
		(at 88.9 236.22 0)
		(unit 1)
		(exclude_from_sim no)
		(in_bom yes)
		(on_board yes)
		(dnp no)
		(property "Reference" "#PWR0324"
			(at 88.9 240.03 0)
			(effects
				(font
					(size 1.27 1.27)
				)
				(hide yes)
			)
		)
		(property "Value" "VDDAUX"
			(at 88.9 232.41 0)
			(effects
				(font
					(size 1.27 1.27)
				)
			)
		)
		(property "Footprint" ""
			(at 88.9 236.22 0)
			(effects
				(font
					(size 1.27 1.27)
				)
				(hide yes)
			)
		)
		(property "Datasheet" ""
			(at 88.9 236.22 0)
			(effects
				(font
					(size 1.27 1.27)
				)
				(hide yes)
			)
		)
		(property "Description" ""
			(at 88.9 236.22 0)
			(effects
				(font
					(size 1.27 1.27)
				)
				(hide yes)
			)
		)
		(pin "1"
		)
		(instances
			(project "polarfire-som"
				(path ""
					(reference "#PWR0324")
					(unit 1)
				)
			)
		)
	)
	(symbol
		(lib_id "antmicroResistors0402:R_0R_0402")
		(at 74.93 135.89 180)
		(unit 1)
		(exclude_from_sim no)
		(in_bom yes)
		(on_board yes)
		(dnp no)
		(fields_autoplaced yes)
		(property "Reference" "R7"
			(at 72.39 129.54 0)
			(effects
				(font
					(size 1.27 1.27)
					(thickness 0.15)
				)
			)
		)
		(property "Value" "R_0R_0402"
			(at 54.61 123.19 0)
			(effects
				(font
					(size 1.27 1.27)
					(thickness 0.15)
				)
				(justify left bottom)
				(hide yes)
			)
		)
		(property "Footprint" "antmicro-footprints:R_0402_1005Metric"
			(at 54.61 120.65 0)
			(effects
				(font
					(size 1.27 1.27)
					(thickness 0.15)
				)
				(justify left bottom)
				(hide yes)
			)
		)
		(property "Datasheet" "https://industrial.panasonic.com/cdbs/www-data/pdf/RDA0000/AOA0000C301.pdf"
			(at 54.61 118.11 0)
			(effects
				(font
					(size 1.27 1.27)
					(thickness 0.15)
				)
				(justify left bottom)
				(hide yes)
			)
		)
		(property "Description" "SMD Chip Resistor, Jumper, 0 ohm, 100 mW, 0402 [1005 Metric], Thick Film, General Purpose"
			(at 74.93 135.89 0)
			(effects
				(font
					(size 1.27 1.27)
				)
				(hide yes)
			)
		)
		(property "MPN" "ERJ2GE0R00X"
			(at 54.61 115.57 0)
			(effects
				(font
					(size 1.27 1.27)
					(thickness 0.15)
				)
				(justify left bottom)
				(hide yes)
			)
		)
		(property "Manufacturer" "Panasonic"
			(at 54.61 113.03 0)
			(effects
				(font
					(size 1.27 1.27)
					(thickness 0.15)
				)
				(justify left bottom)
				(hide yes)
			)
		)
		(property "License" "Apache-2.0"
			(at 54.61 110.49 0)
			(effects
				(font
					(size 1.27 1.27)
					(thickness 0.15)
				)
				(justify left bottom)
				(hide yes)
			)
		)
		(property "Author" "Antmicro"
			(at 54.61 107.95 0)
			(effects
				(font
					(size 1.27 1.27)
					(thickness 0.15)
				)
				(justify left bottom)
				(hide yes)
			)
		)
		(property "Val" "0R"
			(at 72.39 132.08 0)
			(effects
				(font
					(size 1.27 1.27)
					(thickness 0.15)
				)
			)
		)
		(property "Tolerance" "~"
			(at 54.61 125.73 0)
			(effects
				(font
					(size 1.27 1.27)
				)
				(justify left bottom)
				(hide yes)
			)
		)
		(property "Current" "1A"
			(at 54.61 105.41 0)
			(effects
				(font
					(size 1.27 1.27)
					(thickness 0.15)
				)
				(justify left bottom)
				(hide yes)
			)
		)
		(property "Public" ""
			(at 54.61 105.41 0)
			(effects
				(font
					(size 1.27 1.27)
				)
				(justify left bottom)
				(hide yes)
			)
		)
		(pin "1"
		)
		(pin "2"
		)
		(instances
			(project "polarfire-som"
				(path ""
					(reference "R7")
					(unit 1)
				)
			)
		)
	)
	(symbol
		(lib_id "antmicroPMICPowerDistributionSwitchesLoadDrivers:TPS2117DRLR")
		(at 64.77 243.84 0)
		(unit 1)
		(exclude_from_sim no)
		(in_bom yes)
		(on_board yes)
		(dnp no)
		(property "Reference" "U5"
			(at 73.66 236.855 0)
			(effects
				(font
					(size 1.27 1.27)
					(thickness 0.15)
				)
			)
		)
		(property "Value" "TPS2117DRLR"
			(at 73.66 239.395 0)
			(effects
				(font
					(size 1.27 1.27)
					(thickness 0.15)
				)
			)
		)
		(property "Footprint" "antmicro-footprints:SOT-583"
			(at 99.06 248.92 0)
			(effects
				(font
					(size 1.27 1.27)
					(thickness 0.15)
				)
				(justify left bottom)
				(hide yes)
			)
		)
		(property "Datasheet" "https://www.ti.com/lit/ds/symlink/tps2117.pdf"
			(at 99.06 251.46 0)
			(effects
				(font
					(size 1.27 1.27)
					(thickness 0.15)
				)
				(justify left bottom)
				(hide yes)
			)
		)
		(property "Description" "TPS2117 1.6-V to 5.5-V, 4-A Low IQ Power Mux With Manual and Priority Switchover"
			(at 64.77 243.84 0)
			(effects
				(font
					(size 1.27 1.27)
				)
				(hide yes)
			)
		)
		(property "Manufacturer" "Texas Instruments"
			(at 99.06 254 0)
			(effects
				(font
					(size 1.27 1.27)
					(thickness 0.15)
				)
				(justify left bottom)
				(hide yes)
			)
		)
		(property "MPN" "TPS2117DRLR"
			(at 99.06 256.54 0)
			(effects
				(font
					(size 1.27 1.27)
					(thickness 0.15)
				)
				(justify left bottom)
				(hide yes)
			)
		)
		(property "Author" "Antmicro"
			(at 99.06 259.08 0)
			(effects
				(font
					(size 1.27 1.27)
					(thickness 0.15)
				)
				(justify left bottom)
				(hide yes)
			)
		)
		(property "License" "Apache-2.0"
			(at 99.06 261.62 0)
			(effects
				(font
					(size 1.27 1.27)
					(thickness 0.15)
				)
				(justify left bottom)
				(hide yes)
			)
		)
		(pin "1"
		)
		(pin "2"
		)
		(pin "3"
		)
		(pin "4"
		)
		(pin "5"
		)
		(pin "6"
		)
		(pin "7"
		)
		(pin "8"
		)
		(instances
			(project "polarfire-som"
				(path ""
					(reference "U5")
					(unit 1)
				)
			)
		)
	)
	(symbol
		(lib_id "antmicroTestPoints:TP_0.75mm_SMD")
		(at 283.21 214.63 0)
		(unit 1)
		(exclude_from_sim no)
		(in_bom no)
		(on_board yes)
		(dnp no)
		(property "Reference" "TP37"
			(at 290.195 214.63 0)
			(effects
				(font
					(size 1.27 1.27)
					(thickness 0.15)
				)
			)
		)
		(property "Value" "TP_0.75mm_SMD"
			(at 294.005 218.44 0)
			(effects
				(font
					(size 1.27 1.27)
					(thickness 0.15)
				)
				(justify left bottom)
				(hide yes)
			)
		)
		(property "Footprint" "antmicro-footprints:TP_SMD_0.75mm"
			(at 294.005 220.98 0)
			(effects
				(font
					(size 1.27 1.27)
					(thickness 0.15)
				)
				(justify left bottom)
				(hide yes)
			)
		)
		(property "Datasheet" ""
			(at 300.99 227.33 0)
			(effects
				(font
					(size 1.27 1.27)
					(thickness 0.15)
				)
				(justify left bottom)
				(hide yes)
			)
		)
		(property "Description" "SMT test point"
			(at 283.21 214.63 0)
			(effects
				(font
					(size 1.27 1.27)
				)
				(hide yes)
			)
		)
		(property "MPN" ""
			(at 294.005 226.06 0)
			(effects
				(font
					(size 1.27 1.27)
					(thickness 0.15)
				)
				(justify left bottom)
				(hide yes)
			)
		)
		(property "Manufacturer" ""
			(at 294.005 220.98 0)
			(effects
				(font
					(size 1.27 1.27)
					(thickness 0.15)
				)
				(justify left bottom)
				(hide yes)
			)
		)
		(property "Author" "Antmicro"
			(at 294.005 223.52 0)
			(effects
				(font
					(size 1.27 1.27)
					(thickness 0.15)
				)
				(justify left bottom)
				(hide yes)
			)
		)
		(property "License" "Apache-2.0"
			(at 294.005 226.06 0)
			(effects
				(font
					(size 1.27 1.27)
					(thickness 0.15)
				)
				(justify left bottom)
				(hide yes)
			)
		)
		(property "Public" "False"
			(at 293.37 228.6 0)
			(effects
				(font
					(size 1.27 1.27)
				)
				(justify left bottom)
				(hide yes)
			)
		)
		(pin "1"
		)
		(instances
			(project "polarfire-som"
				(path ""
					(reference "TP37")
					(unit 1)
				)
			)
		)
	)
	(symbol
		(lib_id "antmicropower:GND")
		(at 173.99 76.2 0)
		(unit 1)
		(exclude_from_sim no)
		(in_bom yes)
		(on_board yes)
		(dnp no)
		(fields_autoplaced yes)
		(property "Reference" "#PWR086"
			(at 182.88 78.74 0)
			(effects
				(font
					(size 1.27 1.27)
					(thickness 0.15)
				)
				(justify left bottom)
				(hide yes)
			)
		)
		(property "Value" "GND"
			(at 173.99 81.28 0)
			(effects
				(font
					(size 1.27 1.27)
					(thickness 0.15)
				)
			)
		)
		(property "Footprint" ""
			(at 182.88 83.82 0)
			(effects
				(font
					(size 1.27 1.27)
					(thickness 0.15)
				)
				(justify left bottom)
				(hide yes)
			)
		)
		(property "Datasheet" ""
			(at 182.88 88.9 0)
			(effects
				(font
					(size 1.27 1.27)
					(thickness 0.15)
				)
				(justify left bottom)
				(hide yes)
			)
		)
		(property "Description" ""
			(at 173.99 76.2 0)
			(effects
				(font
					(size 1.27 1.27)
				)
				(hide yes)
			)
		)
		(property "Author" "Antmicro"
			(at 182.88 83.82 0)
			(effects
				(font
					(size 1.27 1.27)
					(thickness 0.15)
				)
				(justify left bottom)
				(hide yes)
			)
		)
		(property "License" "Apache-2.0"
			(at 182.88 86.36 0)
			(effects
				(font
					(size 1.27 1.27)
					(thickness 0.15)
				)
				(justify left bottom)
				(hide yes)
			)
		)
		(pin "1"
		)
		(instances
			(project "polarfire-som"
				(path ""
					(reference "#PWR086")
					(unit 1)
				)
			)
		)
	)
	(symbol
		(lib_id "antmicropower:GND")
		(at 262.89 83.82 0)
		(unit 1)
		(exclude_from_sim no)
		(in_bom yes)
		(on_board yes)
		(dnp no)
		(fields_autoplaced yes)
		(property "Reference" "#PWR0100"
			(at 271.78 86.36 0)
			(effects
				(font
					(size 1.27 1.27)
					(thickness 0.15)
				)
				(justify left bottom)
				(hide yes)
			)
		)
		(property "Value" "GND"
			(at 262.89 88.9 0)
			(effects
				(font
					(size 1.27 1.27)
					(thickness 0.15)
				)
			)
		)
		(property "Footprint" ""
			(at 271.78 91.44 0)
			(effects
				(font
					(size 1.27 1.27)
					(thickness 0.15)
				)
				(justify left bottom)
				(hide yes)
			)
		)
		(property "Datasheet" ""
			(at 271.78 96.52 0)
			(effects
				(font
					(size 1.27 1.27)
					(thickness 0.15)
				)
				(justify left bottom)
				(hide yes)
			)
		)
		(property "Description" ""
			(at 262.89 83.82 0)
			(effects
				(font
					(size 1.27 1.27)
				)
				(hide yes)
			)
		)
		(property "Author" "Antmicro"
			(at 271.78 91.44 0)
			(effects
				(font
					(size 1.27 1.27)
					(thickness 0.15)
				)
				(justify left bottom)
				(hide yes)
			)
		)
		(property "License" "Apache-2.0"
			(at 271.78 93.98 0)
			(effects
				(font
					(size 1.27 1.27)
					(thickness 0.15)
				)
				(justify left bottom)
				(hide yes)
			)
		)
		(pin "1"
		)
		(instances
			(project "polarfire-som"
				(path ""
					(reference "#PWR0100")
					(unit 1)
				)
			)
		)
	)
	(symbol
		(lib_id "antmicroCapacitors0402:C_100n_0402")
		(at 207.01 215.9 90)
		(unit 1)
		(exclude_from_sim no)
		(in_bom yes)
		(on_board yes)
		(dnp no)
		(fields_autoplaced yes)
		(property "Reference" "C94"
			(at 210.185 212.0836 90)
			(effects
				(font
					(size 1.27 1.27)
					(thickness 0.15)
				)
				(justify right)
			)
		)
		(property "Value" "C_100n_0402"
			(at 217.17 195.58 0)
			(effects
				(font
					(size 1.27 1.27)
					(thickness 0.15)
				)
				(justify left bottom)
				(hide yes)
			)
		)
		(property "Footprint" "antmicro-footprints:C_0402_1005Metric"
			(at 219.71 195.58 0)
			(effects
				(font
					(size 1.27 1.27)
					(thickness 0.15)
				)
				(justify left bottom)
				(hide yes)
			)
		)
		(property "Datasheet" "https://www.murata.com/products/productdetail?partno=GRM155R61H104KE14%23"
			(at 222.25 195.58 0)
			(effects
				(font
					(size 1.27 1.27)
					(thickness 0.15)
				)
				(justify left bottom)
				(hide yes)
			)
		)
		(property "Description" "SMD Multilayer Ceramic Capacitor, 0.1 µF, 50 V, 0402 [1005 Metric], ± 10%, X5R, GRM Series"
			(at 207.01 215.9 0)
			(effects
				(font
					(size 1.27 1.27)
				)
				(hide yes)
			)
		)
		(property "MPN" "GRM155R61H104KE14D"
			(at 224.79 195.58 0)
			(effects
				(font
					(size 1.27 1.27)
					(thickness 0.15)
				)
				(justify left bottom)
				(hide yes)
			)
		)
		(property "Manufacturer" "Murata"
			(at 227.33 195.58 0)
			(effects
				(font
					(size 1.27 1.27)
					(thickness 0.15)
				)
				(justify left bottom)
				(hide yes)
			)
		)
		(property "License" "Apache-2.0"
			(at 229.87 195.58 0)
			(effects
				(font
					(size 1.27 1.27)
					(thickness 0.15)
				)
				(justify left bottom)
				(hide yes)
			)
		)
		(property "Author" "Antmicro"
			(at 232.41 195.58 0)
			(effects
				(font
					(size 1.27 1.27)
					(thickness 0.15)
				)
				(justify left bottom)
				(hide yes)
			)
		)
		(property "Val" "100n"
			(at 210.185 214.6236 90)
			(effects
				(font
					(size 1.27 1.27)
					(thickness 0.15)
				)
				(justify right)
			)
		)
		(property "Voltage" "50V"
			(at 234.95 195.58 0)
			(effects
				(font
					(size 1.27 1.27)
				)
				(justify left bottom)
				(hide yes)
			)
		)
		(property "Dielectric" "X5R"
			(at 237.49 195.58 0)
			(effects
				(font
					(size 1.27 1.27)
				)
				(justify left bottom)
				(hide yes)
			)
		)
		(property "Public" ""
			(at 240.03 195.58 0)
			(effects
				(font
					(size 1.27 1.27)
				)
				(justify left bottom)
				(hide yes)
			)
		)
		(pin "1"
		)
		(pin "2"
		)
		(instances
			(project "polarfire-som"
				(path ""
					(reference "C94")
					(unit 1)
				)
			)
		)
	)
	(symbol
		(lib_id "antmicroResistors0402:R_0R_0402")
		(at 102.87 54.61 180)
		(unit 1)
		(exclude_from_sim no)
		(in_bom yes)
		(on_board yes)
		(dnp no)
		(property "Reference" "R94"
			(at 96.52 53.34 0)
			(effects
				(font
					(size 1.27 1.27)
					(thickness 0.15)
				)
			)
		)
		(property "Value" "R_0R_0402"
			(at 82.55 41.91 0)
			(effects
				(font
					(size 1.27 1.27)
					(thickness 0.15)
				)
				(justify left bottom)
				(hide yes)
			)
		)
		(property "Footprint" "antmicro-footprints:R_0402_1005Metric"
			(at 82.55 39.37 0)
			(effects
				(font
					(size 1.27 1.27)
					(thickness 0.15)
				)
				(justify left bottom)
				(hide yes)
			)
		)
		(property "Datasheet" "https://industrial.panasonic.com/cdbs/www-data/pdf/RDA0000/AOA0000C301.pdf"
			(at 82.55 36.83 0)
			(effects
				(font
					(size 1.27 1.27)
					(thickness 0.15)
				)
				(justify left bottom)
				(hide yes)
			)
		)
		(property "Description" "SMD Chip Resistor, Jumper, 0 ohm, 100 mW, 0402 [1005 Metric], Thick Film, General Purpose"
			(at 102.87 54.61 0)
			(effects
				(font
					(size 1.27 1.27)
				)
				(hide yes)
			)
		)
		(property "MPN" "ERJ2GE0R00X"
			(at 82.55 34.29 0)
			(effects
				(font
					(size 1.27 1.27)
					(thickness 0.15)
				)
				(justify left bottom)
				(hide yes)
			)
		)
		(property "Manufacturer" "Panasonic"
			(at 82.55 31.75 0)
			(effects
				(font
					(size 1.27 1.27)
					(thickness 0.15)
				)
				(justify left bottom)
				(hide yes)
			)
		)
		(property "License" "Apache-2.0"
			(at 82.55 29.21 0)
			(effects
				(font
					(size 1.27 1.27)
					(thickness 0.15)
				)
				(justify left bottom)
				(hide yes)
			)
		)
		(property "Author" "Antmicro"
			(at 82.55 26.67 0)
			(effects
				(font
					(size 1.27 1.27)
					(thickness 0.15)
				)
				(justify left bottom)
				(hide yes)
			)
		)
		(property "Val" "0R"
			(at 104.14 53.34 0)
			(effects
				(font
					(size 1.27 1.27)
					(thickness 0.15)
				)
			)
		)
		(property "Tolerance" "~"
			(at 82.55 44.45 0)
			(effects
				(font
					(size 1.27 1.27)
				)
				(justify left bottom)
				(hide yes)
			)
		)
		(property "Current" "1A"
			(at 82.55 24.13 0)
			(effects
				(font
					(size 1.27 1.27)
					(thickness 0.15)
				)
				(justify left bottom)
				(hide yes)
			)
		)
		(property "Public" ""
			(at 82.55 24.13 0)
			(effects
				(font
					(size 1.27 1.27)
				)
				(justify left bottom)
				(hide yes)
			)
		)
		(pin "1"
		)
		(pin "2"
		)
		(instances
			(project "polarfire-som"
				(path ""
					(reference "R94")
					(unit 1)
				)
			)
		)
	)
	(symbol
		(lib_id "antmicropower:GND")
		(at 55.88 72.39 0)
		(unit 1)
		(exclude_from_sim no)
		(in_bom yes)
		(on_board yes)
		(dnp no)
		(property "Reference" "#PWR067"
			(at 64.77 74.93 0)
			(effects
				(font
					(size 1.27 1.27)
					(thickness 0.15)
				)
				(justify left bottom)
				(hide yes)
			)
		)
		(property "Value" "GND"
			(at 55.88 76.2 0)
			(effects
				(font
					(size 1.27 1.27)
					(thickness 0.15)
				)
			)
		)
		(property "Footprint" ""
			(at 64.77 80.01 0)
			(effects
				(font
					(size 1.27 1.27)
					(thickness 0.15)
				)
				(justify left bottom)
				(hide yes)
			)
		)
		(property "Datasheet" ""
			(at 64.77 85.09 0)
			(effects
				(font
					(size 1.27 1.27)
					(thickness 0.15)
				)
				(justify left bottom)
				(hide yes)
			)
		)
		(property "Description" ""
			(at 55.88 72.39 0)
			(effects
				(font
					(size 1.27 1.27)
				)
				(hide yes)
			)
		)
		(property "Author" "Antmicro"
			(at 64.77 80.01 0)
			(effects
				(font
					(size 1.27 1.27)
					(thickness 0.15)
				)
				(justify left bottom)
				(hide yes)
			)
		)
		(property "License" "Apache-2.0"
			(at 64.77 82.55 0)
			(effects
				(font
					(size 1.27 1.27)
					(thickness 0.15)
				)
				(justify left bottom)
				(hide yes)
			)
		)
		(pin "1"
		)
		(instances
			(project "polarfire-som"
				(path ""
					(reference "#PWR067")
					(unit 1)
				)
			)
		)
	)
	(symbol
		(lib_id "antmicropower:GND")
		(at 85.09 219.71 0)
		(unit 1)
		(exclude_from_sim no)
		(in_bom yes)
		(on_board yes)
		(dnp no)
		(property "Reference" "#PWR075"
			(at 93.98 222.25 0)
			(effects
				(font
					(size 1.27 1.27)
					(thickness 0.15)
				)
				(justify left bottom)
				(hide yes)
			)
		)
		(property "Value" "GND"
			(at 85.09 223.52 0)
			(effects
				(font
					(size 1.27 1.27)
					(thickness 0.15)
				)
			)
		)
		(property "Footprint" ""
			(at 93.98 227.33 0)
			(effects
				(font
					(size 1.27 1.27)
					(thickness 0.15)
				)
				(justify left bottom)
				(hide yes)
			)
		)
		(property "Datasheet" ""
			(at 93.98 232.41 0)
			(effects
				(font
					(size 1.27 1.27)
					(thickness 0.15)
				)
				(justify left bottom)
				(hide yes)
			)
		)
		(property "Description" ""
			(at 85.09 219.71 0)
			(effects
				(font
					(size 1.27 1.27)
				)
				(hide yes)
			)
		)
		(property "Author" "Antmicro"
			(at 93.98 227.33 0)
			(effects
				(font
					(size 1.27 1.27)
					(thickness 0.15)
				)
				(justify left bottom)
				(hide yes)
			)
		)
		(property "License" "Apache-2.0"
			(at 93.98 229.87 0)
			(effects
				(font
					(size 1.27 1.27)
					(thickness 0.15)
				)
				(justify left bottom)
				(hide yes)
			)
		)
		(pin "1"
		)
		(instances
			(project "polarfire-som"
				(path ""
					(reference "#PWR075")
					(unit 1)
				)
			)
		)
	)
	(symbol
		(lib_id "antmicropower:+5V")
		(at 354.33 134.62 0)
		(unit 1)
		(exclude_from_sim no)
		(in_bom yes)
		(on_board yes)
		(dnp no)
		(property "Reference" "#PWR0279"
			(at 369.57 137.16 0)
			(effects
				(font
					(size 1.27 1.27)
					(thickness 0.15)
				)
				(justify left bottom)
				(hide yes)
			)
		)
		(property "Value" "+5V"
			(at 354.33 130.81 0)
			(effects
				(font
					(size 1.27 1.27)
					(thickness 0.15)
				)
			)
		)
		(property "Footprint" ""
			(at 369.57 142.24 0)
			(effects
				(font
					(size 1.27 1.27)
					(thickness 0.15)
				)
				(justify left bottom)
				(hide yes)
			)
		)
		(property "Datasheet" ""
			(at 369.57 144.78 0)
			(effects
				(font
					(size 1.27 1.27)
					(thickness 0.15)
				)
				(justify left bottom)
				(hide yes)
			)
		)
		(property "Description" ""
			(at 354.33 134.62 0)
			(effects
				(font
					(size 1.27 1.27)
				)
				(hide yes)
			)
		)
		(property "Author" "Antmicro"
			(at 369.57 142.24 0)
			(effects
				(font
					(size 1.27 1.27)
					(thickness 0.15)
				)
				(justify left bottom)
				(hide yes)
			)
		)
		(property "License" "Apache-2.0"
			(at 369.57 144.78 0)
			(effects
				(font
					(size 1.27 1.27)
					(thickness 0.15)
				)
				(justify left bottom)
				(hide yes)
			)
		)
		(pin "1"
		)
		(instances
			(project "polarfire-som"
				(path ""
					(reference "#PWR0279")
					(unit 1)
				)
			)
		)
	)
	(symbol
		(lib_id "antmicroTestPoints:TP_0.75mm_SMD")
		(at 173.99 153.67 0)
		(unit 1)
		(exclude_from_sim no)
		(in_bom no)
		(on_board yes)
		(dnp no)
		(property "Reference" "TP39"
			(at 180.975 153.67 0)
			(effects
				(font
					(size 1.27 1.27)
					(thickness 0.15)
				)
			)
		)
		(property "Value" "TP_0.75mm_SMD"
			(at 184.785 157.48 0)
			(effects
				(font
					(size 1.27 1.27)
					(thickness 0.15)
				)
				(justify left bottom)
				(hide yes)
			)
		)
		(property "Footprint" "antmicro-footprints:TP_SMD_0.75mm"
			(at 184.785 160.02 0)
			(effects
				(font
					(size 1.27 1.27)
					(thickness 0.15)
				)
				(justify left bottom)
				(hide yes)
			)
		)
		(property "Datasheet" ""
			(at 191.77 166.37 0)
			(effects
				(font
					(size 1.27 1.27)
					(thickness 0.15)
				)
				(justify left bottom)
				(hide yes)
			)
		)
		(property "Description" "SMT test point"
			(at 173.99 153.67 0)
			(effects
				(font
					(size 1.27 1.27)
				)
				(hide yes)
			)
		)
		(property "MPN" ""
			(at 184.785 165.1 0)
			(effects
				(font
					(size 1.27 1.27)
					(thickness 0.15)
				)
				(justify left bottom)
				(hide yes)
			)
		)
		(property "Manufacturer" ""
			(at 184.785 160.02 0)
			(effects
				(font
					(size 1.27 1.27)
					(thickness 0.15)
				)
				(justify left bottom)
				(hide yes)
			)
		)
		(property "Author" "Antmicro"
			(at 184.785 162.56 0)
			(effects
				(font
					(size 1.27 1.27)
					(thickness 0.15)
				)
				(justify left bottom)
				(hide yes)
			)
		)
		(property "License" "Apache-2.0"
			(at 184.785 165.1 0)
			(effects
				(font
					(size 1.27 1.27)
					(thickness 0.15)
				)
				(justify left bottom)
				(hide yes)
			)
		)
		(property "Public" "False"
			(at 184.15 167.64 0)
			(effects
				(font
					(size 1.27 1.27)
				)
				(justify left bottom)
				(hide yes)
			)
		)
		(pin "1"
		)
		(instances
			(project "polarfire-som"
				(path ""
					(reference "TP39")
					(unit 1)
				)
			)
		)
	)
	(symbol
		(lib_id "antmicroCapacitors0402:C_22u_0402")
		(at 271.78 67.31 90)
		(unit 1)
		(exclude_from_sim no)
		(in_bom yes)
		(on_board yes)
		(dnp no)
		(fields_autoplaced yes)
		(property "Reference" "C107"
			(at 274.32 63.4936 90)
			(effects
				(font
					(size 1.27 1.27)
					(thickness 0.15)
				)
				(justify right)
			)
		)
		(property "Value" "C_22u_0402"
			(at 281.94 46.99 0)
			(effects
				(font
					(size 1.27 1.27)
					(thickness 0.15)
				)
				(justify left bottom)
				(hide yes)
			)
		)
		(property "Footprint" "antmicro-footprints:C_0402_1005Metric"
			(at 284.48 46.99 0)
			(effects
				(font
					(size 1.27 1.27)
					(thickness 0.15)
				)
				(justify left bottom)
				(hide yes)
			)
		)
		(property "Datasheet" "https://www.murata.com/products/productdetail?partno=GRM158R60J226ME01%23"
			(at 287.02 46.99 0)
			(effects
				(font
					(size 1.27 1.27)
					(thickness 0.15)
				)
				(justify left bottom)
				(hide yes)
			)
		)
		(property "Description" "SMD Multilayer Ceramic Capacitor, 22 uF, 4 V, 0402 [1005 Metric], X6S"
			(at 271.78 67.31 0)
			(effects
				(font
					(size 1.27 1.27)
				)
				(hide yes)
			)
		)
		(property "MPN" "GRM158R60J226ME01D"
			(at 289.56 46.99 0)
			(effects
				(font
					(size 1.27 1.27)
					(thickness 0.15)
				)
				(justify left bottom)
				(hide yes)
			)
		)
		(property "Manufacturer" "Murata"
			(at 292.1 46.99 0)
			(effects
				(font
					(size 1.27 1.27)
					(thickness 0.15)
				)
				(justify left bottom)
				(hide yes)
			)
		)
		(property "License" "Apache-2.0"
			(at 294.64 46.99 0)
			(effects
				(font
					(size 1.27 1.27)
					(thickness 0.15)
				)
				(justify left bottom)
				(hide yes)
			)
		)
		(property "Author" "Antmicro"
			(at 297.18 46.99 0)
			(effects
				(font
					(size 1.27 1.27)
					(thickness 0.15)
				)
				(justify left bottom)
				(hide yes)
			)
		)
		(property "Val" "22u"
			(at 274.32 66.0336 90)
			(effects
				(font
					(size 1.27 1.27)
					(thickness 0.15)
				)
				(justify right)
			)
		)
		(property "Voltage" ""
			(at 299.72 46.99 0)
			(effects
				(font
					(size 1.27 1.27)
				)
				(justify left bottom)
				(hide yes)
			)
		)
		(property "Dielectric" ""
			(at 302.26 46.99 0)
			(effects
				(font
					(size 1.27 1.27)
				)
				(justify left bottom)
				(hide yes)
			)
		)
		(property "Public" ""
			(at 304.8 46.99 0)
			(effects
				(font
					(size 1.27 1.27)
				)
				(justify left bottom)
				(hide yes)
			)
		)
		(pin "2"
		)
		(pin "1"
		)
		(instances
			(project "polarfire-som"
				(path ""
					(reference "C107")
					(unit 1)
				)
			)
		)
	)
	(symbol
		(lib_id "antmicropower:GND")
		(at 189.23 219.71 0)
		(unit 1)
		(exclude_from_sim no)
		(in_bom yes)
		(on_board yes)
		(dnp no)
		(fields_autoplaced yes)
		(property "Reference" "#PWR089"
			(at 189.23 226.06 0)
			(effects
				(font
					(size 1.27 1.27)
				)
				(hide yes)
			)
		)
		(property "Value" "GND"
			(at 189.23 224.155 0)
			(effects
				(font
					(size 1.27 1.27)
					(thickness 0.15)
				)
			)
		)
		(property "Footprint" ""
			(at 198.12 227.33 0)
			(effects
				(font
					(size 1.27 1.27)
					(thickness 0.15)
				)
				(justify left bottom)
				(hide yes)
			)
		)
		(property "Datasheet" ""
			(at 198.12 232.41 0)
			(effects
				(font
					(size 1.27 1.27)
					(thickness 0.15)
				)
				(justify left bottom)
				(hide yes)
			)
		)
		(property "Description" ""
			(at 189.23 219.71 0)
			(effects
				(font
					(size 1.27 1.27)
				)
				(hide yes)
			)
		)
		(property "Author" "Antmicro"
			(at 198.12 227.33 0)
			(effects
				(font
					(size 1.27 1.27)
					(thickness 0.15)
				)
				(justify left bottom)
				(hide yes)
			)
		)
		(property "License" "Apache-2.0"
			(at 198.12 229.87 0)
			(effects
				(font
					(size 1.27 1.27)
					(thickness 0.15)
				)
				(justify left bottom)
				(hide yes)
			)
		)
		(pin "1"
		)
		(instances
			(project "polarfire-som"
				(path ""
					(reference "#PWR089")
					(unit 1)
				)
			)
		)
	)
	(symbol
		(lib_id "antmicroCapacitors0402:C_470n_0402")
		(at 189.23 234.95 90)
		(unit 1)
		(exclude_from_sim no)
		(in_bom yes)
		(on_board yes)
		(dnp no)
		(fields_autoplaced yes)
		(property "Reference" "C89"
			(at 191.77 231.1336 90)
			(effects
				(font
					(size 1.27 1.27)
					(thickness 0.15)
				)
				(justify right)
			)
		)
		(property "Value" "C_470n_0402"
			(at 199.39 214.63 0)
			(effects
				(font
					(size 1.27 1.27)
					(thickness 0.15)
				)
				(justify left bottom)
				(hide yes)
			)
		)
		(property "Footprint" "antmicro-footprints:C_0402_1005Metric"
			(at 201.93 214.63 0)
			(effects
				(font
					(size 1.27 1.27)
					(thickness 0.15)
				)
				(justify left bottom)
				(hide yes)
			)
		)
		(property "Datasheet" "https://product.tdk.com/en/search/capacitor/ceramic/mlcc/info?part_no=C1005X5R1E474M050BB"
			(at 204.47 214.63 0)
			(effects
				(font
					(size 1.27 1.27)
					(thickness 0.15)
				)
				(justify left bottom)
				(hide yes)
			)
		)
		(property "Description" "SMD Multilayer Ceramic Capacitor, 0.47 µF, 25 V, 0402 [1005 Metric], ± 20%, X5R, C"
			(at 189.23 234.95 0)
			(effects
				(font
					(size 1.27 1.27)
				)
				(hide yes)
			)
		)
		(property "MPN" "C1005X5R1E474M050BB"
			(at 207.01 214.63 0)
			(effects
				(font
					(size 1.27 1.27)
					(thickness 0.15)
				)
				(justify left bottom)
				(hide yes)
			)
		)
		(property "Manufacturer" "TDK"
			(at 209.55 214.63 0)
			(effects
				(font
					(size 1.27 1.27)
					(thickness 0.15)
				)
				(justify left bottom)
				(hide yes)
			)
		)
		(property "License" "Apache-2.0"
			(at 212.09 214.63 0)
			(effects
				(font
					(size 1.27 1.27)
					(thickness 0.15)
				)
				(justify left bottom)
				(hide yes)
			)
		)
		(property "Author" "Antmicro"
			(at 214.63 214.63 0)
			(effects
				(font
					(size 1.27 1.27)
					(thickness 0.15)
				)
				(justify left bottom)
				(hide yes)
			)
		)
		(property "Val" "470n"
			(at 191.77 233.6736 90)
			(effects
				(font
					(size 1.27 1.27)
					(thickness 0.15)
				)
				(justify right)
			)
		)
		(property "Voltage" ""
			(at 217.17 214.63 0)
			(effects
				(font
					(size 1.27 1.27)
				)
				(justify left bottom)
				(hide yes)
			)
		)
		(property "Dielectric" ""
			(at 219.71 214.63 0)
			(effects
				(font
					(size 1.27 1.27)
				)
				(justify left bottom)
				(hide yes)
			)
		)
		(property "Public" ""
			(at 222.25 214.63 0)
			(effects
				(font
					(size 1.27 1.27)
				)
				(justify left bottom)
				(hide yes)
			)
		)
		(pin "2"
		)
		(pin "1"
		)
		(instances
			(project "polarfire-som"
				(path ""
					(reference "C89")
					(unit 1)
				)
			)
		)
	)
	(symbol
		(lib_id "antmicroPMICVoltageRegulatorsDCDCSwitchingRegulators:MP8869S")
		(at 231.14 214.63 0)
		(unit 1)
		(exclude_from_sim no)
		(in_bom yes)
		(on_board yes)
		(dnp no)
		(fields_autoplaced yes)
		(property "Reference" "U8"
			(at 233.3341 212.09 0)
			(effects
				(font
					(size 1.27 1.27)
					(thickness 0.15)
				)
				(justify left)
			)
		)
		(property "Value" "MP8869S"
			(at 233.3341 214.63 0)
			(effects
				(font
					(size 1.27 1.27)
					(thickness 0.15)
				)
				(justify left)
			)
		)
		(property "Footprint" "antmicro-footprints:MPS_QFN-14_MP8869S"
			(at 256.54 226.06 0)
			(effects
				(font
					(size 1.27 1.27)
					(thickness 0.15)
				)
				(justify left bottom)
				(hide yes)
			)
		)
		(property "Datasheet" "https://www.mouser.com/datasheet/2/277/MP8869S-2946178.pdf"
			(at 256.54 228.6 0)
			(effects
				(font
					(size 1.27 1.27)
					(thickness 0.15)
				)
				(justify left bottom)
				(hide yes)
			)
		)
		(property "Description" "DC-DC Switching Synchronous Buck Regulator, 2.85V-18V in, 600mV to 5.5V out, 12A, 500kHz, QFN-14"
			(at 231.14 214.63 0)
			(effects
				(font
					(size 1.27 1.27)
				)
				(hide yes)
			)
		)
		(property "MPN" "MP8869SGL-P"
			(at 256.54 231.14 0)
			(effects
				(font
					(size 1.27 1.27)
					(thickness 0.15)
				)
				(justify left bottom)
				(hide yes)
			)
		)
		(property "Manufacturer" "Monolithic Power Systems"
			(at 256.54 233.68 0)
			(effects
				(font
					(size 1.27 1.27)
					(thickness 0.15)
				)
				(justify left bottom)
				(hide yes)
			)
		)
		(property "Author" "Antmicro"
			(at 256.54 236.22 0)
			(effects
				(font
					(size 1.27 1.27)
					(thickness 0.15)
				)
				(justify left bottom)
				(hide yes)
			)
		)
		(property "License" "Apache-2.0"
			(at 256.54 238.76 0)
			(effects
				(font
					(size 1.27 1.27)
					(thickness 0.15)
				)
				(justify left bottom)
				(hide yes)
			)
		)
		(pin "12"
		)
		(pin "10"
		)
		(pin "13"
		)
		(pin "9"
		)
		(pin "11"
		)
		(pin "7"
		)
		(pin "4"
		)
		(pin "3"
		)
		(pin "1"
		)
		(pin "6"
		)
		(pin "5"
		)
		(pin "14"
		)
		(pin "8"
		)
		(pin "2"
		)
		(instances
			(project "polarfire-som"
				(path ""
					(reference "U8")
					(unit 1)
				)
			)
		)
	)
	(symbol
		(lib_id "antmicroCapacitors0402:C_100n_0402")
		(at 33.02 59.69 90)
		(unit 1)
		(exclude_from_sim no)
		(in_bom yes)
		(on_board yes)
		(dnp no)
		(property "Reference" "C83"
			(at 34.29 54.61 90)
			(effects
				(font
					(size 1.27 1.27)
					(thickness 0.15)
				)
				(justify right)
			)
		)
		(property "Value" "C_100n_0402"
			(at 43.18 39.37 0)
			(effects
				(font
					(size 1.27 1.27)
					(thickness 0.15)
				)
				(justify left bottom)
				(hide yes)
			)
		)
		(property "Footprint" "antmicro-footprints:C_0402_1005Metric"
			(at 45.72 39.37 0)
			(effects
				(font
					(size 1.27 1.27)
					(thickness 0.15)
				)
				(justify left bottom)
				(hide yes)
			)
		)
		(property "Datasheet" "https://www.murata.com/products/productdetail?partno=GRM155R61H104KE14%23"
			(at 48.26 39.37 0)
			(effects
				(font
					(size 1.27 1.27)
					(thickness 0.15)
				)
				(justify left bottom)
				(hide yes)
			)
		)
		(property "Description" "SMD Multilayer Ceramic Capacitor, 0.1 µF, 50 V, 0402 [1005 Metric], ± 10%, X5R, GRM Series"
			(at 33.02 59.69 0)
			(effects
				(font
					(size 1.27 1.27)
				)
				(hide yes)
			)
		)
		(property "MPN" "GRM155R61H104KE14D"
			(at 50.8 39.37 0)
			(effects
				(font
					(size 1.27 1.27)
					(thickness 0.15)
				)
				(justify left bottom)
				(hide yes)
			)
		)
		(property "Manufacturer" "Murata"
			(at 53.34 39.37 0)
			(effects
				(font
					(size 1.27 1.27)
					(thickness 0.15)
				)
				(justify left bottom)
				(hide yes)
			)
		)
		(property "License" "Apache-2.0"
			(at 55.88 39.37 0)
			(effects
				(font
					(size 1.27 1.27)
					(thickness 0.15)
				)
				(justify left bottom)
				(hide yes)
			)
		)
		(property "Author" "Antmicro"
			(at 58.42 39.37 0)
			(effects
				(font
					(size 1.27 1.27)
					(thickness 0.15)
				)
				(justify left bottom)
				(hide yes)
			)
		)
		(property "Val" "100n"
			(at 39.37 58.42 90)
			(effects
				(font
					(size 1.27 1.27)
					(thickness 0.15)
				)
				(justify left bottom)
			)
		)
		(property "Voltage" "50V"
			(at 60.96 39.37 0)
			(effects
				(font
					(size 1.27 1.27)
				)
				(justify left bottom)
				(hide yes)
			)
		)
		(property "Dielectric" "X5R"
			(at 63.5 39.37 0)
			(effects
				(font
					(size 1.27 1.27)
				)
				(justify left bottom)
				(hide yes)
			)
		)
		(property "Public" ""
			(at 66.04 39.37 0)
			(effects
				(font
					(size 1.27 1.27)
				)
				(justify left bottom)
				(hide yes)
			)
		)
		(pin "1"
		)
		(pin "2"
		)
		(instances
			(project "polarfire-som"
				(path ""
					(reference "C83")
					(unit 1)
				)
			)
		)
	)
	(symbol
		(lib_id "antmicroPMICPowerDistributionSwitchesLoadDrivers:TPS2117DRLR")
		(at 64.77 210.82 0)
		(unit 1)
		(exclude_from_sim no)
		(in_bom yes)
		(on_board yes)
		(dnp no)
		(property "Reference" "U4"
			(at 73.66 203.2 0)
			(effects
				(font
					(size 1.27 1.27)
					(thickness 0.15)
				)
			)
		)
		(property "Value" "TPS2117DRLR"
			(at 73.66 205.74 0)
			(effects
				(font
					(size 1.27 1.27)
					(thickness 0.15)
				)
			)
		)
		(property "Footprint" "antmicro-footprints:SOT-583"
			(at 99.06 215.9 0)
			(effects
				(font
					(size 1.27 1.27)
					(thickness 0.15)
				)
				(justify left bottom)
				(hide yes)
			)
		)
		(property "Datasheet" "https://www.ti.com/lit/ds/symlink/tps2117.pdf"
			(at 99.06 218.44 0)
			(effects
				(font
					(size 1.27 1.27)
					(thickness 0.15)
				)
				(justify left bottom)
				(hide yes)
			)
		)
		(property "Description" "TPS2117 1.6-V to 5.5-V, 4-A Low IQ Power Mux With Manual and Priority Switchover"
			(at 64.77 210.82 0)
			(effects
				(font
					(size 1.27 1.27)
				)
				(hide yes)
			)
		)
		(property "Manufacturer" "Texas Instruments"
			(at 99.06 220.98 0)
			(effects
				(font
					(size 1.27 1.27)
					(thickness 0.15)
				)
				(justify left bottom)
				(hide yes)
			)
		)
		(property "MPN" "TPS2117DRLR"
			(at 99.06 223.52 0)
			(effects
				(font
					(size 1.27 1.27)
					(thickness 0.15)
				)
				(justify left bottom)
				(hide yes)
			)
		)
		(property "Author" "Antmicro"
			(at 99.06 226.06 0)
			(effects
				(font
					(size 1.27 1.27)
					(thickness 0.15)
				)
				(justify left bottom)
				(hide yes)
			)
		)
		(property "License" "Apache-2.0"
			(at 99.06 228.6 0)
			(effects
				(font
					(size 1.27 1.27)
					(thickness 0.15)
				)
				(justify left bottom)
				(hide yes)
			)
		)
		(pin "1"
		)
		(pin "2"
		)
		(pin "3"
		)
		(pin "4"
		)
		(pin "5"
		)
		(pin "6"
		)
		(pin "7"
		)
		(pin "8"
		)
		(instances
			(project "polarfire-som"
				(path ""
					(reference "U4")
					(unit 1)
				)
			)
		)
	)
	(symbol
		(lib_id "antmicroTestPoints:TP_0.75mm_SMD")
		(at 158.75 134.62 180)
		(unit 1)
		(exclude_from_sim no)
		(in_bom no)
		(on_board yes)
		(dnp no)
		(property "Reference" "TP34"
			(at 151.765 134.62 0)
			(effects
				(font
					(size 1.27 1.27)
					(thickness 0.15)
				)
			)
		)
		(property "Value" "TP_0.75mm_SMD"
			(at 147.955 130.81 0)
			(effects
				(font
					(size 1.27 1.27)
					(thickness 0.15)
				)
				(justify left bottom)
				(hide yes)
			)
		)
		(property "Footprint" "antmicro-footprints:TP_SMD_0.75mm"
			(at 147.955 128.27 0)
			(effects
				(font
					(size 1.27 1.27)
					(thickness 0.15)
				)
				(justify left bottom)
				(hide yes)
			)
		)
		(property "Datasheet" ""
			(at 140.97 121.92 0)
			(effects
				(font
					(size 1.27 1.27)
					(thickness 0.15)
				)
				(justify left bottom)
				(hide yes)
			)
		)
		(property "Description" "SMT test point"
			(at 158.75 134.62 0)
			(effects
				(font
					(size 1.27 1.27)
				)
				(hide yes)
			)
		)
		(property "MPN" ""
			(at 147.955 123.19 0)
			(effects
				(font
					(size 1.27 1.27)
					(thickness 0.15)
				)
				(justify left bottom)
				(hide yes)
			)
		)
		(property "Manufacturer" ""
			(at 147.955 128.27 0)
			(effects
				(font
					(size 1.27 1.27)
					(thickness 0.15)
				)
				(justify left bottom)
				(hide yes)
			)
		)
		(property "Author" "Antmicro"
			(at 147.955 125.73 0)
			(effects
				(font
					(size 1.27 1.27)
					(thickness 0.15)
				)
				(justify left bottom)
				(hide yes)
			)
		)
		(property "License" "Apache-2.0"
			(at 147.955 123.19 0)
			(effects
				(font
					(size 1.27 1.27)
					(thickness 0.15)
				)
				(justify left bottom)
				(hide yes)
			)
		)
		(property "Public" "False"
			(at 148.59 120.65 0)
			(effects
				(font
					(size 1.27 1.27)
				)
				(justify left bottom)
				(hide yes)
			)
		)
		(pin "1"
		)
		(instances
			(project "polarfire-som"
				(path ""
					(reference "TP34")
					(unit 1)
				)
			)
		)
	)
	(symbol
		(lib_id "antmicroCapacitors0402:C_100n_0402")
		(at 234.95 205.74 0)
		(unit 1)
		(exclude_from_sim no)
		(in_bom yes)
		(on_board yes)
		(dnp no)
		(fields_autoplaced yes)
		(property "Reference" "C95"
			(at 237.4963 198.755 0)
			(effects
				(font
					(size 1.27 1.27)
					(thickness 0.15)
				)
			)
		)
		(property "Value" "C_100n_0402"
			(at 255.27 215.9 0)
			(effects
				(font
					(size 1.27 1.27)
					(thickness 0.15)
				)
				(justify left bottom)
				(hide yes)
			)
		)
		(property "Footprint" "antmicro-footprints:C_0402_1005Metric"
			(at 255.27 218.44 0)
			(effects
				(font
					(size 1.27 1.27)
					(thickness 0.15)
				)
				(justify left bottom)
				(hide yes)
			)
		)
		(property "Datasheet" "https://www.murata.com/products/productdetail?partno=GRM155R61H104KE14%23"
			(at 255.27 220.98 0)
			(effects
				(font
					(size 1.27 1.27)
					(thickness 0.15)
				)
				(justify left bottom)
				(hide yes)
			)
		)
		(property "Description" "SMD Multilayer Ceramic Capacitor, 0.1 µF, 50 V, 0402 [1005 Metric], ± 10%, X5R, GRM Series"
			(at 234.95 205.74 0)
			(effects
				(font
					(size 1.27 1.27)
				)
				(hide yes)
			)
		)
		(property "MPN" "GRM155R61H104KE14D"
			(at 255.27 223.52 0)
			(effects
				(font
					(size 1.27 1.27)
					(thickness 0.15)
				)
				(justify left bottom)
				(hide yes)
			)
		)
		(property "Manufacturer" "Murata"
			(at 255.27 226.06 0)
			(effects
				(font
					(size 1.27 1.27)
					(thickness 0.15)
				)
				(justify left bottom)
				(hide yes)
			)
		)
		(property "License" "Apache-2.0"
			(at 255.27 228.6 0)
			(effects
				(font
					(size 1.27 1.27)
					(thickness 0.15)
				)
				(justify left bottom)
				(hide yes)
			)
		)
		(property "Author" "Antmicro"
			(at 255.27 231.14 0)
			(effects
				(font
					(size 1.27 1.27)
					(thickness 0.15)
				)
				(justify left bottom)
				(hide yes)
			)
		)
		(property "Val" "100n"
			(at 237.4963 201.295 0)
			(effects
				(font
					(size 1.27 1.27)
					(thickness 0.15)
				)
			)
		)
		(property "Voltage" "50V"
			(at 255.27 233.68 0)
			(effects
				(font
					(size 1.27 1.27)
				)
				(justify left bottom)
				(hide yes)
			)
		)
		(property "Dielectric" "X5R"
			(at 255.27 236.22 0)
			(effects
				(font
					(size 1.27 1.27)
				)
				(justify left bottom)
				(hide yes)
			)
		)
		(property "Public" ""
			(at 255.27 238.76 0)
			(effects
				(font
					(size 1.27 1.27)
				)
				(justify left bottom)
				(hide yes)
			)
		)
		(pin "2"
		)
		(pin "1"
		)
		(instances
			(project "polarfire-som"
				(path ""
					(reference "C95")
					(unit 1)
				)
			)
		)
	)
	(symbol
		(lib_id "antmicroCapacitors0402:C_22u_0402")
		(at 256.54 227.33 90)
		(unit 1)
		(exclude_from_sim no)
		(in_bom yes)
		(on_board yes)
		(dnp no)
		(property "Reference" "C97"
			(at 257.175 222.885 90)
			(effects
				(font
					(size 1.27 1.27)
					(thickness 0.15)
				)
				(justify right)
			)
		)
		(property "Value" "C_22u_0402"
			(at 266.7 207.01 0)
			(effects
				(font
					(size 1.27 1.27)
					(thickness 0.15)
				)
				(justify left bottom)
				(hide yes)
			)
		)
		(property "Footprint" "antmicro-footprints:C_0402_1005Metric"
			(at 269.24 207.01 0)
			(effects
				(font
					(size 1.27 1.27)
					(thickness 0.15)
				)
				(justify left bottom)
				(hide yes)
			)
		)
		(property "Datasheet" "https://www.murata.com/products/productdetail?partno=GRM158R60J226ME01%23"
			(at 271.78 207.01 0)
			(effects
				(font
					(size 1.27 1.27)
					(thickness 0.15)
				)
				(justify left bottom)
				(hide yes)
			)
		)
		(property "Description" "SMD Multilayer Ceramic Capacitor, 22 uF, 4 V, 0402 [1005 Metric], X6S"
			(at 256.54 227.33 0)
			(effects
				(font
					(size 1.27 1.27)
				)
				(hide yes)
			)
		)
		(property "MPN" "GRM158R60J226ME01D"
			(at 274.32 207.01 0)
			(effects
				(font
					(size 1.27 1.27)
					(thickness 0.15)
				)
				(justify left bottom)
				(hide yes)
			)
		)
		(property "Manufacturer" "Murata"
			(at 276.86 207.01 0)
			(effects
				(font
					(size 1.27 1.27)
					(thickness 0.15)
				)
				(justify left bottom)
				(hide yes)
			)
		)
		(property "License" "Apache-2.0"
			(at 279.4 207.01 0)
			(effects
				(font
					(size 1.27 1.27)
					(thickness 0.15)
				)
				(justify left bottom)
				(hide yes)
			)
		)
		(property "Author" "Antmicro"
			(at 281.94 207.01 0)
			(effects
				(font
					(size 1.27 1.27)
					(thickness 0.15)
				)
				(justify left bottom)
				(hide yes)
			)
		)
		(property "Val" "22u"
			(at 257.175 226.695 90)
			(effects
				(font
					(size 1.27 1.27)
					(thickness 0.15)
				)
				(justify right)
			)
		)
		(property "Voltage" ""
			(at 284.48 207.01 0)
			(effects
				(font
					(size 1.27 1.27)
				)
				(justify left bottom)
				(hide yes)
			)
		)
		(property "Dielectric" ""
			(at 287.02 207.01 0)
			(effects
				(font
					(size 1.27 1.27)
				)
				(justify left bottom)
				(hide yes)
			)
		)
		(property "Public" ""
			(at 289.56 207.01 0)
			(effects
				(font
					(size 1.27 1.27)
				)
				(justify left bottom)
				(hide yes)
			)
		)
		(pin "2"
		)
		(pin "1"
		)
		(instances
			(project "polarfire-som"
				(path ""
					(reference "C97")
					(unit 1)
				)
			)
		)
	)
	(symbol
		(lib_id "antmicropower:GND")
		(at 195.58 100.33 0)
		(unit 1)
		(exclude_from_sim no)
		(in_bom yes)
		(on_board yes)
		(dnp no)
		(property "Reference" "#PWR092"
			(at 204.47 102.87 0)
			(effects
				(font
					(size 1.27 1.27)
					(thickness 0.15)
				)
				(justify left bottom)
				(hide yes)
			)
		)
		(property "Value" "GND"
			(at 195.58 104.775 0)
			(effects
				(font
					(size 1.27 1.27)
					(thickness 0.15)
				)
			)
		)
		(property "Footprint" ""
			(at 204.47 107.95 0)
			(effects
				(font
					(size 1.27 1.27)
					(thickness 0.15)
				)
				(justify left bottom)
				(hide yes)
			)
		)
		(property "Datasheet" ""
			(at 204.47 113.03 0)
			(effects
				(font
					(size 1.27 1.27)
					(thickness 0.15)
				)
				(justify left bottom)
				(hide yes)
			)
		)
		(property "Description" ""
			(at 195.58 100.33 0)
			(effects
				(font
					(size 1.27 1.27)
				)
				(hide yes)
			)
		)
		(property "Author" "Antmicro"
			(at 204.47 107.95 0)
			(effects
				(font
					(size 1.27 1.27)
					(thickness 0.15)
				)
				(justify left bottom)
				(hide yes)
			)
		)
		(property "License" "Apache-2.0"
			(at 204.47 110.49 0)
			(effects
				(font
					(size 1.27 1.27)
					(thickness 0.15)
				)
				(justify left bottom)
				(hide yes)
			)
		)
		(pin "1"
		)
		(instances
			(project "polarfire-som"
				(path ""
					(reference "#PWR092")
					(unit 1)
				)
			)
		)
	)
	(symbol
		(lib_id "antmicropower:+3V3")
		(at 24.13 53.34 0)
		(unit 1)
		(exclude_from_sim no)
		(in_bom yes)
		(on_board yes)
		(dnp no)
		(property "Reference" "#PWR062"
			(at 39.37 55.88 0)
			(effects
				(font
					(size 1.27 1.27)
					(thickness 0.15)
				)
				(justify left bottom)
				(hide yes)
			)
		)
		(property "Value" "+3V3"
			(at 24.13 49.53 0)
			(effects
				(font
					(size 1.27 1.27)
					(thickness 0.15)
				)
			)
		)
		(property "Footprint" ""
			(at 39.37 60.96 0)
			(effects
				(font
					(size 1.27 1.27)
					(thickness 0.15)
				)
				(justify left bottom)
				(hide yes)
			)
		)
		(property "Datasheet" ""
			(at 39.37 63.5 0)
			(effects
				(font
					(size 1.27 1.27)
					(thickness 0.15)
				)
				(justify left bottom)
				(hide yes)
			)
		)
		(property "Description" ""
			(at 24.13 53.34 0)
			(effects
				(font
					(size 1.27 1.27)
				)
				(hide yes)
			)
		)
		(property "Author" "Antmicro"
			(at 39.37 60.96 0)
			(effects
				(font
					(size 1.27 1.27)
					(thickness 0.15)
				)
				(justify left bottom)
				(hide yes)
			)
		)
		(property "License" "Apache-2.0"
			(at 39.37 63.5 0)
			(effects
				(font
					(size 1.27 1.27)
					(thickness 0.15)
				)
				(justify left bottom)
				(hide yes)
			)
		)
		(pin "1"
		)
		(instances
			(project "polarfire-som"
				(path ""
					(reference "#PWR062")
					(unit 1)
				)
			)
		)
	)
	(symbol
		(lib_id "antmicropower:+5V")
		(at 365.76 120.65 0)
		(unit 1)
		(exclude_from_sim no)
		(in_bom yes)
		(on_board yes)
		(dnp no)
		(property "Reference" "#PWR0271"
			(at 381 123.19 0)
			(effects
				(font
					(size 1.27 1.27)
					(thickness 0.15)
				)
				(justify left bottom)
				(hide yes)
			)
		)
		(property "Value" "+5V"
			(at 365.76 116.84 0)
			(effects
				(font
					(size 1.27 1.27)
					(thickness 0.15)
				)
			)
		)
		(property "Footprint" ""
			(at 381 128.27 0)
			(effects
				(font
					(size 1.27 1.27)
					(thickness 0.15)
				)
				(justify left bottom)
				(hide yes)
			)
		)
		(property "Datasheet" ""
			(at 381 130.81 0)
			(effects
				(font
					(size 1.27 1.27)
					(thickness 0.15)
				)
				(justify left bottom)
				(hide yes)
			)
		)
		(property "Description" ""
			(at 365.76 120.65 0)
			(effects
				(font
					(size 1.27 1.27)
				)
				(hide yes)
			)
		)
		(property "Author" "Antmicro"
			(at 381 128.27 0)
			(effects
				(font
					(size 1.27 1.27)
					(thickness 0.15)
				)
				(justify left bottom)
				(hide yes)
			)
		)
		(property "License" "Apache-2.0"
			(at 381 130.81 0)
			(effects
				(font
					(size 1.27 1.27)
					(thickness 0.15)
				)
				(justify left bottom)
				(hide yes)
			)
		)
		(pin "1"
		)
		(instances
			(project "polarfire-som"
				(path ""
					(reference "#PWR0271")
					(unit 1)
				)
			)
		)
	)
	(symbol
		(lib_id "antmicroTestPoints:TP_0.75mm_SMD")
		(at 173.99 151.13 0)
		(unit 1)
		(exclude_from_sim no)
		(in_bom no)
		(on_board yes)
		(dnp no)
		(property "Reference" "TP24"
			(at 180.975 151.13 0)
			(effects
				(font
					(size 1.27 1.27)
					(thickness 0.15)
				)
			)
		)
		(property "Value" "TP_0.75mm_SMD"
			(at 184.785 154.94 0)
			(effects
				(font
					(size 1.27 1.27)
					(thickness 0.15)
				)
				(justify left bottom)
				(hide yes)
			)
		)
		(property "Footprint" "antmicro-footprints:TP_SMD_0.75mm"
			(at 184.785 157.48 0)
			(effects
				(font
					(size 1.27 1.27)
					(thickness 0.15)
				)
				(justify left bottom)
				(hide yes)
			)
		)
		(property "Datasheet" ""
			(at 191.77 163.83 0)
			(effects
				(font
					(size 1.27 1.27)
					(thickness 0.15)
				)
				(justify left bottom)
				(hide yes)
			)
		)
		(property "Description" "SMT test point"
			(at 173.99 151.13 0)
			(effects
				(font
					(size 1.27 1.27)
				)
				(hide yes)
			)
		)
		(property "MPN" ""
			(at 184.785 162.56 0)
			(effects
				(font
					(size 1.27 1.27)
					(thickness 0.15)
				)
				(justify left bottom)
				(hide yes)
			)
		)
		(property "Manufacturer" ""
			(at 184.785 157.48 0)
			(effects
				(font
					(size 1.27 1.27)
					(thickness 0.15)
				)
				(justify left bottom)
				(hide yes)
			)
		)
		(property "Author" "Antmicro"
			(at 184.785 160.02 0)
			(effects
				(font
					(size 1.27 1.27)
					(thickness 0.15)
				)
				(justify left bottom)
				(hide yes)
			)
		)
		(property "License" "Apache-2.0"
			(at 184.785 162.56 0)
			(effects
				(font
					(size 1.27 1.27)
					(thickness 0.15)
				)
				(justify left bottom)
				(hide yes)
			)
		)
		(property "Public" "False"
			(at 184.15 165.1 0)
			(effects
				(font
					(size 1.27 1.27)
				)
				(justify left bottom)
				(hide yes)
			)
		)
		(pin "1"
		)
		(instances
			(project "polarfire-som"
				(path ""
					(reference "TP24")
					(unit 1)
				)
			)
		)
	)
	(symbol
		(lib_id "antmicroCapacitors0402:C_22u_0402")
		(at 191.77 74.93 90)
		(unit 1)
		(exclude_from_sim no)
		(in_bom yes)
		(on_board yes)
		(dnp no)
		(fields_autoplaced yes)
		(property "Reference" "C90"
			(at 194.31 71.1136 90)
			(effects
				(font
					(size 1.27 1.27)
					(thickness 0.15)
				)
				(justify right)
			)
		)
		(property "Value" "C_22u_0402"
			(at 201.93 54.61 0)
			(effects
				(font
					(size 1.27 1.27)
					(thickness 0.15)
				)
				(justify left bottom)
				(hide yes)
			)
		)
		(property "Footprint" "antmicro-footprints:C_0402_1005Metric"
			(at 204.47 54.61 0)
			(effects
				(font
					(size 1.27 1.27)
					(thickness 0.15)
				)
				(justify left bottom)
				(hide yes)
			)
		)
		(property "Datasheet" "https://www.murata.com/products/productdetail?partno=GRM158R60J226ME01%23"
			(at 207.01 54.61 0)
			(effects
				(font
					(size 1.27 1.27)
					(thickness 0.15)
				)
				(justify left bottom)
				(hide yes)
			)
		)
		(property "Description" "SMD Multilayer Ceramic Capacitor, 22 uF, 4 V, 0402 [1005 Metric], X6S"
			(at 191.77 74.93 0)
			(effects
				(font
					(size 1.27 1.27)
				)
				(hide yes)
			)
		)
		(property "MPN" "GRM158R60J226ME01D"
			(at 209.55 54.61 0)
			(effects
				(font
					(size 1.27 1.27)
					(thickness 0.15)
				)
				(justify left bottom)
				(hide yes)
			)
		)
		(property "Manufacturer" "Murata"
			(at 212.09 54.61 0)
			(effects
				(font
					(size 1.27 1.27)
					(thickness 0.15)
				)
				(justify left bottom)
				(hide yes)
			)
		)
		(property "License" "Apache-2.0"
			(at 214.63 54.61 0)
			(effects
				(font
					(size 1.27 1.27)
					(thickness 0.15)
				)
				(justify left bottom)
				(hide yes)
			)
		)
		(property "Author" "Antmicro"
			(at 217.17 54.61 0)
			(effects
				(font
					(size 1.27 1.27)
					(thickness 0.15)
				)
				(justify left bottom)
				(hide yes)
			)
		)
		(property "Val" "22u"
			(at 194.31 73.6536 90)
			(effects
				(font
					(size 1.27 1.27)
					(thickness 0.15)
				)
				(justify right)
			)
		)
		(property "Voltage" ""
			(at 219.71 54.61 0)
			(effects
				(font
					(size 1.27 1.27)
				)
				(justify left bottom)
				(hide yes)
			)
		)
		(property "Dielectric" ""
			(at 222.25 54.61 0)
			(effects
				(font
					(size 1.27 1.27)
				)
				(justify left bottom)
				(hide yes)
			)
		)
		(property "Public" ""
			(at 224.79 54.61 0)
			(effects
				(font
					(size 1.27 1.27)
				)
				(justify left bottom)
				(hide yes)
			)
		)
		(pin "2"
		)
		(pin "1"
		)
		(instances
			(project "polarfire-som"
				(path ""
					(reference "C90")
					(unit 1)
				)
			)
		)
	)
	(symbol
		(lib_id "antmicroTestPoints:TP_0.75mm_SMD")
		(at 279.4 132.08 0)
		(unit 1)
		(exclude_from_sim no)
		(in_bom no)
		(on_board yes)
		(dnp no)
		(property "Reference" "TP21"
			(at 286.385 132.08 0)
			(effects
				(font
					(size 1.27 1.27)
					(thickness 0.15)
				)
			)
		)
		(property "Value" "TP_0.75mm_SMD"
			(at 290.195 135.89 0)
			(effects
				(font
					(size 1.27 1.27)
					(thickness 0.15)
				)
				(justify left bottom)
				(hide yes)
			)
		)
		(property "Footprint" "antmicro-footprints:TP_SMD_0.75mm"
			(at 290.195 138.43 0)
			(effects
				(font
					(size 1.27 1.27)
					(thickness 0.15)
				)
				(justify left bottom)
				(hide yes)
			)
		)
		(property "Datasheet" ""
			(at 297.18 144.78 0)
			(effects
				(font
					(size 1.27 1.27)
					(thickness 0.15)
				)
				(justify left bottom)
				(hide yes)
			)
		)
		(property "Description" "SMT test point"
			(at 279.4 132.08 0)
			(effects
				(font
					(size 1.27 1.27)
				)
				(hide yes)
			)
		)
		(property "MPN" ""
			(at 290.195 143.51 0)
			(effects
				(font
					(size 1.27 1.27)
					(thickness 0.15)
				)
				(justify left bottom)
				(hide yes)
			)
		)
		(property "Manufacturer" ""
			(at 290.195 138.43 0)
			(effects
				(font
					(size 1.27 1.27)
					(thickness 0.15)
				)
				(justify left bottom)
				(hide yes)
			)
		)
		(property "Author" "Antmicro"
			(at 290.195 140.97 0)
			(effects
				(font
					(size 1.27 1.27)
					(thickness 0.15)
				)
				(justify left bottom)
				(hide yes)
			)
		)
		(property "License" "Apache-2.0"
			(at 290.195 143.51 0)
			(effects
				(font
					(size 1.27 1.27)
					(thickness 0.15)
				)
				(justify left bottom)
				(hide yes)
			)
		)
		(property "Public" "False"
			(at 289.56 146.05 0)
			(effects
				(font
					(size 1.27 1.27)
				)
				(justify left bottom)
				(hide yes)
			)
		)
		(pin "1"
		)
		(instances
			(project "polarfire-som"
				(path ""
					(reference "TP21")
					(unit 1)
				)
			)
		)
	)
	(symbol
		(lib_id "antmicroCapacitors0402:C_22u_0402")
		(at 273.05 227.33 90)
		(unit 1)
		(exclude_from_sim no)
		(in_bom yes)
		(on_board yes)
		(dnp no)
		(property "Reference" "C105"
			(at 273.685 222.885 90)
			(effects
				(font
					(size 1.27 1.27)
					(thickness 0.15)
				)
				(justify right)
			)
		)
		(property "Value" "C_22u_0402"
			(at 283.21 207.01 0)
			(effects
				(font
					(size 1.27 1.27)
					(thickness 0.15)
				)
				(justify left bottom)
				(hide yes)
			)
		)
		(property "Footprint" "antmicro-footprints:C_0402_1005Metric"
			(at 285.75 207.01 0)
			(effects
				(font
					(size 1.27 1.27)
					(thickness 0.15)
				)
				(justify left bottom)
				(hide yes)
			)
		)
		(property "Datasheet" "https://www.murata.com/products/productdetail?partno=GRM158R60J226ME01%23"
			(at 288.29 207.01 0)
			(effects
				(font
					(size 1.27 1.27)
					(thickness 0.15)
				)
				(justify left bottom)
				(hide yes)
			)
		)
		(property "Description" "SMD Multilayer Ceramic Capacitor, 22 uF, 4 V, 0402 [1005 Metric], X6S"
			(at 273.05 227.33 0)
			(effects
				(font
					(size 1.27 1.27)
				)
				(hide yes)
			)
		)
		(property "MPN" "GRM158R60J226ME01D"
			(at 290.83 207.01 0)
			(effects
				(font
					(size 1.27 1.27)
					(thickness 0.15)
				)
				(justify left bottom)
				(hide yes)
			)
		)
		(property "Manufacturer" "Murata"
			(at 293.37 207.01 0)
			(effects
				(font
					(size 1.27 1.27)
					(thickness 0.15)
				)
				(justify left bottom)
				(hide yes)
			)
		)
		(property "License" "Apache-2.0"
			(at 295.91 207.01 0)
			(effects
				(font
					(size 1.27 1.27)
					(thickness 0.15)
				)
				(justify left bottom)
				(hide yes)
			)
		)
		(property "Author" "Antmicro"
			(at 298.45 207.01 0)
			(effects
				(font
					(size 1.27 1.27)
					(thickness 0.15)
				)
				(justify left bottom)
				(hide yes)
			)
		)
		(property "Val" "22u"
			(at 273.685 226.695 90)
			(effects
				(font
					(size 1.27 1.27)
					(thickness 0.15)
				)
				(justify right)
			)
		)
		(property "Voltage" ""
			(at 300.99 207.01 0)
			(effects
				(font
					(size 1.27 1.27)
				)
				(justify left bottom)
				(hide yes)
			)
		)
		(property "Dielectric" ""
			(at 303.53 207.01 0)
			(effects
				(font
					(size 1.27 1.27)
				)
				(justify left bottom)
				(hide yes)
			)
		)
		(property "Public" ""
			(at 306.07 207.01 0)
			(effects
				(font
					(size 1.27 1.27)
				)
				(justify left bottom)
				(hide yes)
			)
		)
		(pin "2"
		)
		(pin "1"
		)
		(instances
			(project "polarfire-som"
				(path ""
					(reference "C105")
					(unit 1)
				)
			)
		)
	)
	(symbol
		(lib_id "antmicroCapacitors0402:C_22u_0402")
		(at 261.62 52.07 90)
		(unit 1)
		(exclude_from_sim no)
		(in_bom yes)
		(on_board yes)
		(dnp no)
		(fields_autoplaced yes)
		(property "Reference" "C99"
			(at 264.16 48.2536 90)
			(effects
				(font
					(size 1.27 1.27)
					(thickness 0.15)
				)
				(justify right)
			)
		)
		(property "Value" "C_22u_0402"
			(at 271.78 31.75 0)
			(effects
				(font
					(size 1.27 1.27)
					(thickness 0.15)
				)
				(justify left bottom)
				(hide yes)
			)
		)
		(property "Footprint" "antmicro-footprints:C_0402_1005Metric"
			(at 274.32 31.75 0)
			(effects
				(font
					(size 1.27 1.27)
					(thickness 0.15)
				)
				(justify left bottom)
				(hide yes)
			)
		)
		(property "Datasheet" "https://www.murata.com/products/productdetail?partno=GRM158R60J226ME01%23"
			(at 276.86 31.75 0)
			(effects
				(font
					(size 1.27 1.27)
					(thickness 0.15)
				)
				(justify left bottom)
				(hide yes)
			)
		)
		(property "Description" "SMD Multilayer Ceramic Capacitor, 22 uF, 4 V, 0402 [1005 Metric], X6S"
			(at 261.62 52.07 0)
			(effects
				(font
					(size 1.27 1.27)
				)
				(hide yes)
			)
		)
		(property "MPN" "GRM158R60J226ME01D"
			(at 279.4 31.75 0)
			(effects
				(font
					(size 1.27 1.27)
					(thickness 0.15)
				)
				(justify left bottom)
				(hide yes)
			)
		)
		(property "Manufacturer" "Murata"
			(at 281.94 31.75 0)
			(effects
				(font
					(size 1.27 1.27)
					(thickness 0.15)
				)
				(justify left bottom)
				(hide yes)
			)
		)
		(property "License" "Apache-2.0"
			(at 284.48 31.75 0)
			(effects
				(font
					(size 1.27 1.27)
					(thickness 0.15)
				)
				(justify left bottom)
				(hide yes)
			)
		)
		(property "Author" "Antmicro"
			(at 287.02 31.75 0)
			(effects
				(font
					(size 1.27 1.27)
					(thickness 0.15)
				)
				(justify left bottom)
				(hide yes)
			)
		)
		(property "Val" "22u"
			(at 264.16 50.7936 90)
			(effects
				(font
					(size 1.27 1.27)
					(thickness 0.15)
				)
				(justify right)
			)
		)
		(property "Voltage" ""
			(at 289.56 31.75 0)
			(effects
				(font
					(size 1.27 1.27)
				)
				(justify left bottom)
				(hide yes)
			)
		)
		(property "Dielectric" ""
			(at 292.1 31.75 0)
			(effects
				(font
					(size 1.27 1.27)
				)
				(justify left bottom)
				(hide yes)
			)
		)
		(property "Public" ""
			(at 294.64 31.75 0)
			(effects
				(font
					(size 1.27 1.27)
				)
				(justify left bottom)
				(hide yes)
			)
		)
		(pin "2"
		)
		(pin "1"
		)
		(instances
			(project "polarfire-som"
				(path ""
					(reference "C99")
					(unit 1)
				)
			)
		)
	)
	(symbol
		(lib_id "antmicropower:GND")
		(at 63.5 144.78 0)
		(unit 1)
		(exclude_from_sim no)
		(in_bom yes)
		(on_board yes)
		(dnp no)
		(fields_autoplaced yes)
		(property "Reference" "#PWR069"
			(at 72.39 147.32 0)
			(effects
				(font
					(size 1.27 1.27)
					(thickness 0.15)
				)
				(justify left bottom)
				(hide yes)
			)
		)
		(property "Value" "GND"
			(at 63.5 149.86 0)
			(effects
				(font
					(size 1.27 1.27)
					(thickness 0.15)
				)
			)
		)
		(property "Footprint" ""
			(at 72.39 152.4 0)
			(effects
				(font
					(size 1.27 1.27)
					(thickness 0.15)
				)
				(justify left bottom)
				(hide yes)
			)
		)
		(property "Datasheet" ""
			(at 72.39 157.48 0)
			(effects
				(font
					(size 1.27 1.27)
					(thickness 0.15)
				)
				(justify left bottom)
				(hide yes)
			)
		)
		(property "Description" ""
			(at 63.5 144.78 0)
			(effects
				(font
					(size 1.27 1.27)
				)
				(hide yes)
			)
		)
		(property "Author" "Antmicro"
			(at 72.39 152.4 0)
			(effects
				(font
					(size 1.27 1.27)
					(thickness 0.15)
				)
				(justify left bottom)
				(hide yes)
			)
		)
		(property "License" "Apache-2.0"
			(at 72.39 154.94 0)
			(effects
				(font
					(size 1.27 1.27)
					(thickness 0.15)
				)
				(justify left bottom)
				(hide yes)
			)
		)
		(pin "1"
		)
		(instances
			(project "polarfire-som"
				(path ""
					(reference "#PWR069")
					(unit 1)
				)
			)
		)
	)
	(symbol
		(lib_id "antmicroTestPoints:TP_0.75mm_SMD")
		(at 158.75 137.16 180)
		(unit 1)
		(exclude_from_sim no)
		(in_bom no)
		(on_board yes)
		(dnp no)
		(property "Reference" "TP36"
			(at 151.765 137.16 0)
			(effects
				(font
					(size 1.27 1.27)
					(thickness 0.15)
				)
			)
		)
		(property "Value" "TP_0.75mm_SMD"
			(at 147.955 133.35 0)
			(effects
				(font
					(size 1.27 1.27)
					(thickness 0.15)
				)
				(justify left bottom)
				(hide yes)
			)
		)
		(property "Footprint" "antmicro-footprints:TP_SMD_0.75mm"
			(at 147.955 130.81 0)
			(effects
				(font
					(size 1.27 1.27)
					(thickness 0.15)
				)
				(justify left bottom)
				(hide yes)
			)
		)
		(property "Datasheet" ""
			(at 140.97 124.46 0)
			(effects
				(font
					(size 1.27 1.27)
					(thickness 0.15)
				)
				(justify left bottom)
				(hide yes)
			)
		)
		(property "Description" "SMT test point"
			(at 158.75 137.16 0)
			(effects
				(font
					(size 1.27 1.27)
				)
				(hide yes)
			)
		)
		(property "MPN" ""
			(at 147.955 125.73 0)
			(effects
				(font
					(size 1.27 1.27)
					(thickness 0.15)
				)
				(justify left bottom)
				(hide yes)
			)
		)
		(property "Manufacturer" ""
			(at 147.955 130.81 0)
			(effects
				(font
					(size 1.27 1.27)
					(thickness 0.15)
				)
				(justify left bottom)
				(hide yes)
			)
		)
		(property "Author" "Antmicro"
			(at 147.955 128.27 0)
			(effects
				(font
					(size 1.27 1.27)
					(thickness 0.15)
				)
				(justify left bottom)
				(hide yes)
			)
		)
		(property "License" "Apache-2.0"
			(at 147.955 125.73 0)
			(effects
				(font
					(size 1.27 1.27)
					(thickness 0.15)
				)
				(justify left bottom)
				(hide yes)
			)
		)
		(property "Public" "False"
			(at 148.59 123.19 0)
			(effects
				(font
					(size 1.27 1.27)
				)
				(justify left bottom)
				(hide yes)
			)
		)
		(pin "1"
		)
		(instances
			(project "polarfire-som"
				(path ""
					(reference "TP36")
					(unit 1)
				)
			)
		)
	)
	(symbol
		(lib_id "antmicroTestPoints:TP_0.75mm_SMD")
		(at 276.86 107.95 0)
		(unit 1)
		(exclude_from_sim no)
		(in_bom no)
		(on_board yes)
		(dnp no)
		(property "Reference" "TP20"
			(at 283.845 107.95 0)
			(effects
				(font
					(size 1.27 1.27)
					(thickness 0.15)
				)
			)
		)
		(property "Value" "TP_0.75mm_SMD"
			(at 287.655 111.76 0)
			(effects
				(font
					(size 1.27 1.27)
					(thickness 0.15)
				)
				(justify left bottom)
				(hide yes)
			)
		)
		(property "Footprint" "antmicro-footprints:TP_SMD_0.75mm"
			(at 287.655 114.3 0)
			(effects
				(font
					(size 1.27 1.27)
					(thickness 0.15)
				)
				(justify left bottom)
				(hide yes)
			)
		)
		(property "Datasheet" ""
			(at 294.64 120.65 0)
			(effects
				(font
					(size 1.27 1.27)
					(thickness 0.15)
				)
				(justify left bottom)
				(hide yes)
			)
		)
		(property "Description" "SMT test point"
			(at 276.86 107.95 0)
			(effects
				(font
					(size 1.27 1.27)
				)
				(hide yes)
			)
		)
		(property "MPN" ""
			(at 287.655 119.38 0)
			(effects
				(font
					(size 1.27 1.27)
					(thickness 0.15)
				)
				(justify left bottom)
				(hide yes)
			)
		)
		(property "Manufacturer" ""
			(at 287.655 114.3 0)
			(effects
				(font
					(size 1.27 1.27)
					(thickness 0.15)
				)
				(justify left bottom)
				(hide yes)
			)
		)
		(property "Author" "Antmicro"
			(at 287.655 116.84 0)
			(effects
				(font
					(size 1.27 1.27)
					(thickness 0.15)
				)
				(justify left bottom)
				(hide yes)
			)
		)
		(property "License" "Apache-2.0"
			(at 287.655 119.38 0)
			(effects
				(font
					(size 1.27 1.27)
					(thickness 0.15)
				)
				(justify left bottom)
				(hide yes)
			)
		)
		(property "Public" "False"
			(at 287.02 121.92 0)
			(effects
				(font
					(size 1.27 1.27)
				)
				(justify left bottom)
				(hide yes)
			)
		)
		(pin "1"
		)
		(instances
			(project "polarfire-som"
				(path ""
					(reference "TP20")
					(unit 1)
				)
			)
		)
	)
	(symbol
		(lib_id "antmicropower:GND")
		(at 261.62 118.11 0)
		(unit 1)
		(exclude_from_sim no)
		(in_bom yes)
		(on_board yes)
		(dnp no)
		(fields_autoplaced yes)
		(property "Reference" "#PWR0102"
			(at 270.51 120.65 0)
			(effects
				(font
					(size 1.27 1.27)
					(thickness 0.15)
				)
				(justify left bottom)
				(hide yes)
			)
		)
		(property "Value" "GND"
			(at 261.62 123.19 0)
			(effects
				(font
					(size 1.27 1.27)
					(thickness 0.15)
				)
			)
		)
		(property "Footprint" ""
			(at 270.51 125.73 0)
			(effects
				(font
					(size 1.27 1.27)
					(thickness 0.15)
				)
				(justify left bottom)
				(hide yes)
			)
		)
		(property "Datasheet" ""
			(at 270.51 130.81 0)
			(effects
				(font
					(size 1.27 1.27)
					(thickness 0.15)
				)
				(justify left bottom)
				(hide yes)
			)
		)
		(property "Description" ""
			(at 261.62 118.11 0)
			(effects
				(font
					(size 1.27 1.27)
				)
				(hide yes)
			)
		)
		(property "Author" "Antmicro"
			(at 270.51 125.73 0)
			(effects
				(font
					(size 1.27 1.27)
					(thickness 0.15)
				)
				(justify left bottom)
				(hide yes)
			)
		)
		(property "License" "Apache-2.0"
			(at 270.51 128.27 0)
			(effects
				(font
					(size 1.27 1.27)
					(thickness 0.15)
				)
				(justify left bottom)
				(hide yes)
			)
		)
		(pin "1"
		)
		(instances
			(project "polarfire-som"
				(path ""
					(reference "#PWR0102")
					(unit 1)
				)
			)
		)
	)
	(symbol
		(lib_id "antmicroCapacitors0402:C_22n_0402")
		(at 252.73 248.92 90)
		(unit 1)
		(exclude_from_sim no)
		(in_bom yes)
		(on_board yes)
		(dnp no)
		(fields_autoplaced yes)
		(property "Reference" "C96"
			(at 255.905 245.1036 90)
			(effects
				(font
					(size 1.27 1.27)
					(thickness 0.15)
				)
				(justify right)
			)
		)
		(property "Value" "C_22n_0402"
			(at 262.89 228.6 0)
			(effects
				(font
					(size 1.27 1.27)
					(thickness 0.15)
				)
				(justify left bottom)
				(hide yes)
			)
		)
		(property "Footprint" "antmicro-footprints:C_0402_1005Metric"
			(at 265.43 228.6 0)
			(effects
				(font
					(size 1.27 1.27)
					(thickness 0.15)
				)
				(justify left bottom)
				(hide yes)
			)
		)
		(property "Datasheet" "https://www.murata.com/products/productdetail?partno=GCM155R71H223MA55%23"
			(at 267.97 228.6 0)
			(effects
				(font
					(size 1.27 1.27)
					(thickness 0.15)
				)
				(justify left bottom)
				(hide yes)
			)
		)
		(property "Description" "SMD Multilayer Ceramic Capacitors, 0.022 µF, 50 V, 20%, 0402 [1005 Metric], X7R"
			(at 252.73 248.92 0)
			(effects
				(font
					(size 1.27 1.27)
				)
				(hide yes)
			)
		)
		(property "MPN" "GCM155R71H223MA55D"
			(at 270.51 228.6 0)
			(effects
				(font
					(size 1.27 1.27)
					(thickness 0.15)
				)
				(justify left bottom)
				(hide yes)
			)
		)
		(property "Manufacturer" "Murata"
			(at 273.05 228.6 0)
			(effects
				(font
					(size 1.27 1.27)
					(thickness 0.15)
				)
				(justify left bottom)
				(hide yes)
			)
		)
		(property "License" "Apache-2.0"
			(at 275.59 228.6 0)
			(effects
				(font
					(size 1.27 1.27)
					(thickness 0.15)
				)
				(justify left bottom)
				(hide yes)
			)
		)
		(property "Author" "Antmicro"
			(at 278.13 228.6 0)
			(effects
				(font
					(size 1.27 1.27)
					(thickness 0.15)
				)
				(justify left bottom)
				(hide yes)
			)
		)
		(property "Val" "22n"
			(at 255.905 247.6436 90)
			(effects
				(font
					(size 1.27 1.27)
					(thickness 0.15)
				)
				(justify right)
			)
		)
		(property "Voltage" ""
			(at 280.67 228.6 0)
			(effects
				(font
					(size 1.27 1.27)
				)
				(justify left bottom)
				(hide yes)
			)
		)
		(property "Dielectric" ""
			(at 283.21 228.6 0)
			(effects
				(font
					(size 1.27 1.27)
				)
				(justify left bottom)
				(hide yes)
			)
		)
		(property "Public" ""
			(at 285.75 228.6 0)
			(effects
				(font
					(size 1.27 1.27)
				)
				(justify left bottom)
				(hide yes)
			)
		)
		(pin "2"
		)
		(pin "1"
		)
		(instances
			(project "polarfire-som"
				(path ""
					(reference "C96")
					(unit 1)
				)
			)
		)
	)
	(symbol
		(lib_id "antmicroResistors0603:R_0R_22.4A_0603")
		(at 293.37 219.71 0)
		(unit 1)
		(exclude_from_sim no)
		(in_bom yes)
		(on_board yes)
		(dnp no)
		(fields_autoplaced yes)
		(property "Reference" "R20"
			(at 295.91 211.455 0)
			(effects
				(font
					(size 1.27 1.27)
					(thickness 0.15)
				)
			)
		)
		(property "Value" "R_0R_22.4A_0603"
			(at 295.91 210.82 0)
			(effects
				(font
					(size 1.27 1.27)
					(thickness 0.15)
				)
				(hide yes)
			)
		)
		(property "Footprint" "antmicro-footprints:R_0603_1608Metric"
			(at 308.61 229.87 0)
			(effects
				(font
					(size 1.27 1.27)
					(thickness 0.15)
				)
				(justify left bottom)
				(hide yes)
			)
		)
		(property "Datasheet" "https://fscdn.rohm.com/en/products/databook/datasheet/passive/resistor/chip_resistor/pmr-jpw-e.pdf"
			(at 308.61 232.41 0)
			(effects
				(font
					(size 1.27 1.27)
					(thickness 0.15)
				)
				(justify left bottom)
				(hide yes)
			)
		)
		(property "Description" "SMD Chip Resistor"
			(at 293.37 219.71 0)
			(effects
				(font
					(size 1.27 1.27)
				)
				(hide yes)
			)
		)
		(property "MPN" "PMR03EZPJ000"
			(at 308.61 234.95 0)
			(effects
				(font
					(size 1.27 1.27)
					(thickness 0.15)
				)
				(justify left bottom)
				(hide yes)
			)
		)
		(property "Manufacturer" "ROHM Semiconductor"
			(at 308.61 237.49 0)
			(effects
				(font
					(size 1.27 1.27)
					(thickness 0.15)
				)
				(justify left bottom)
				(hide yes)
			)
		)
		(property "Val" "0R"
			(at 295.91 213.995 0)
			(effects
				(font
					(size 1.27 1.27)
					(thickness 0.15)
				)
			)
		)
		(property "Max. Curr." "22.4A"
			(at 295.91 216.535 0)
			(effects
				(font
					(size 1.27 1.27)
					(thickness 0.15)
				)
			)
		)
		(property "Author" "Antmicro"
			(at 308.61 242.57 0)
			(effects
				(font
					(size 1.27 1.27)
					(thickness 0.15)
				)
				(justify left bottom)
				(hide yes)
			)
		)
		(property "License" "Apache-2.0"
			(at 308.61 245.11 0)
			(effects
				(font
					(size 1.27 1.27)
					(thickness 0.15)
				)
				(justify left bottom)
				(hide yes)
			)
		)
		(property "Tolerance" "template_tolerance"
			(at 313.69 229.87 0)
			(effects
				(font
					(size 1.27 1.27)
				)
				(justify left bottom)
				(hide yes)
			)
		)
		(property "Public" ""
			(at 313.69 250.19 0)
			(effects
				(font
					(size 1.27 1.27)
				)
				(justify left bottom)
				(hide yes)
			)
		)
		(pin "2"
		)
		(pin "1"
		)
		(instances
			(project "polarfire-som"
				(path ""
					(reference "R20")
					(unit 1)
				)
			)
		)
	)
	(symbol
		(lib_id "antmicroTestPoints:TP_0.75mm_SMD")
		(at 278.13 73.66 0)
		(unit 1)
		(exclude_from_sim no)
		(in_bom no)
		(on_board yes)
		(dnp no)
		(property "Reference" "TP6"
			(at 285.115 73.66 0)
			(effects
				(font
					(size 1.27 1.27)
					(thickness 0.15)
				)
			)
		)
		(property "Value" "TP_0.75mm_SMD"
			(at 288.925 77.47 0)
			(effects
				(font
					(size 1.27 1.27)
					(thickness 0.15)
				)
				(justify left bottom)
				(hide yes)
			)
		)
		(property "Footprint" "antmicro-footprints:TP_SMD_0.75mm"
			(at 288.925 80.01 0)
			(effects
				(font
					(size 1.27 1.27)
					(thickness 0.15)
				)
				(justify left bottom)
				(hide yes)
			)
		)
		(property "Datasheet" ""
			(at 295.91 86.36 0)
			(effects
				(font
					(size 1.27 1.27)
					(thickness 0.15)
				)
				(justify left bottom)
				(hide yes)
			)
		)
		(property "Description" "SMT test point"
			(at 278.13 73.66 0)
			(effects
				(font
					(size 1.27 1.27)
				)
				(hide yes)
			)
		)
		(property "MPN" ""
			(at 288.925 85.09 0)
			(effects
				(font
					(size 1.27 1.27)
					(thickness 0.15)
				)
				(justify left bottom)
				(hide yes)
			)
		)
		(property "Manufacturer" ""
			(at 288.925 80.01 0)
			(effects
				(font
					(size 1.27 1.27)
					(thickness 0.15)
				)
				(justify left bottom)
				(hide yes)
			)
		)
		(property "Author" "Antmicro"
			(at 288.925 82.55 0)
			(effects
				(font
					(size 1.27 1.27)
					(thickness 0.15)
				)
				(justify left bottom)
				(hide yes)
			)
		)
		(property "License" "Apache-2.0"
			(at 288.925 85.09 0)
			(effects
				(font
					(size 1.27 1.27)
					(thickness 0.15)
				)
				(justify left bottom)
				(hide yes)
			)
		)
		(property "Public" "False"
			(at 288.29 87.63 0)
			(effects
				(font
					(size 1.27 1.27)
				)
				(justify left bottom)
				(hide yes)
			)
		)
		(pin "1"
		)
		(instances
			(project "polarfire-som"
				(path ""
					(reference "TP6")
					(unit 1)
				)
			)
		)
	)
	(symbol
		(lib_id "antmicropower:+1V8")
		(at 53.34 217.17 0)
		(unit 1)
		(exclude_from_sim no)
		(in_bom yes)
		(on_board yes)
		(dnp no)
		(fields_autoplaced yes)
		(property "Reference" "#PWR065"
			(at 68.58 219.71 0)
			(effects
				(font
					(size 1.27 1.27)
					(thickness 0.15)
				)
				(justify left bottom)
				(hide yes)
			)
		)
		(property "Value" "+1V8"
			(at 53.34 212.09 0)
			(effects
				(font
					(size 1.27 1.27)
					(thickness 0.15)
				)
			)
		)
		(property "Footprint" ""
			(at 68.58 224.79 0)
			(effects
				(font
					(size 1.27 1.27)
					(thickness 0.15)
				)
				(justify left bottom)
				(hide yes)
			)
		)
		(property "Datasheet" ""
			(at 68.58 227.33 0)
			(effects
				(font
					(size 1.27 1.27)
					(thickness 0.15)
				)
				(justify left bottom)
				(hide yes)
			)
		)
		(property "Description" ""
			(at 53.34 217.17 0)
			(effects
				(font
					(size 1.27 1.27)
				)
				(hide yes)
			)
		)
		(property "Author" "Antmicro"
			(at 68.58 224.79 0)
			(effects
				(font
					(size 1.27 1.27)
					(thickness 0.15)
				)
				(justify left bottom)
				(hide yes)
			)
		)
		(property "License" "Apache-2.0"
			(at 68.58 227.33 0)
			(effects
				(font
					(size 1.27 1.27)
					(thickness 0.15)
				)
				(justify left bottom)
				(hide yes)
			)
		)
		(pin "1"
		)
		(instances
			(project "polarfire-som"
				(path ""
					(reference "#PWR065")
					(unit 1)
				)
			)
		)
	)
	(symbol
		(lib_id "antmicropower:GND")
		(at 261.62 68.58 0)
		(unit 1)
		(exclude_from_sim no)
		(in_bom yes)
		(on_board yes)
		(dnp no)
		(property "Reference" "#PWR099"
			(at 270.51 71.12 0)
			(effects
				(font
					(size 1.27 1.27)
					(thickness 0.15)
				)
				(justify left bottom)
				(hide yes)
			)
		)
		(property "Value" "GND"
			(at 261.62 72.39 0)
			(effects
				(font
					(size 1.27 1.27)
					(thickness 0.15)
				)
			)
		)
		(property "Footprint" ""
			(at 270.51 76.2 0)
			(effects
				(font
					(size 1.27 1.27)
					(thickness 0.15)
				)
				(justify left bottom)
				(hide yes)
			)
		)
		(property "Datasheet" ""
			(at 270.51 81.28 0)
			(effects
				(font
					(size 1.27 1.27)
					(thickness 0.15)
				)
				(justify left bottom)
				(hide yes)
			)
		)
		(property "Description" ""
			(at 261.62 68.58 0)
			(effects
				(font
					(size 1.27 1.27)
				)
				(hide yes)
			)
		)
		(property "Author" "Antmicro"
			(at 270.51 76.2 0)
			(effects
				(font
					(size 1.27 1.27)
					(thickness 0.15)
				)
				(justify left bottom)
				(hide yes)
			)
		)
		(property "License" "Apache-2.0"
			(at 270.51 78.74 0)
			(effects
				(font
					(size 1.27 1.27)
					(thickness 0.15)
				)
				(justify left bottom)
				(hide yes)
			)
		)
		(pin "1"
		)
		(instances
			(project "polarfire-som"
				(path ""
					(reference "#PWR099")
					(unit 1)
				)
			)
		)
	)
	(symbol
		(lib_id "antmicroFixedInductors:L_1u_3.2A_0805")
		(at 251.46 92.71 0)
		(unit 1)
		(exclude_from_sim no)
		(in_bom yes)
		(on_board yes)
		(dnp no)
		(fields_autoplaced yes)
		(property "Reference" "L4"
			(at 254 87.63 0)
			(effects
				(font
					(size 1.27 1.27)
					(thickness 0.15)
				)
			)
		)
		(property "Value" "L_1u_3.2A_0805"
			(at 265.43 95.25 0)
			(effects
				(font
					(size 1.27 1.27)
					(thickness 0.15)
				)
				(justify left bottom)
				(hide yes)
			)
		)
		(property "Footprint" "antmicro-footprints:L_0805_2012Metric"
			(at 265.43 100.33 0)
			(effects
				(font
					(size 1.27 1.27)
					(thickness 0.15)
				)
				(justify left bottom)
				(hide yes)
			)
		)
		(property "Datasheet" "https://abracon.com/datasheets/AOTA-B201208S.pdf"
			(at 265.43 102.87 0)
			(effects
				(font
					(size 1.27 1.27)
					(thickness 0.15)
				)
				(justify left bottom)
				(hide yes)
			)
		)
		(property "Description" "Power Inductor (SMT), 1 µH, 0.05 ohm, 3.2 A, AOTA-B201208S"
			(at 251.46 92.71 0)
			(effects
				(font
					(size 1.27 1.27)
				)
				(hide yes)
			)
		)
		(property "Val" "1u/3.2A"
			(at 254 90.17 0)
			(effects
				(font
					(size 1.27 1.27)
					(thickness 0.15)
				)
			)
		)
		(property "Manufacturer" "Abracon"
			(at 265.43 105.41 0)
			(effects
				(font
					(size 1.27 1.27)
					(thickness 0.15)
				)
				(justify left bottom)
				(hide yes)
			)
		)
		(property "MPN" "AOTA-B201208S1R0MT "
			(at 265.43 107.95 0)
			(effects
				(font
					(size 1.27 1.27)
					(thickness 0.15)
				)
				(justify left bottom)
				(hide yes)
			)
		)
		(property "ISat" "3.5 A"
			(at 265.43 109.22 0)
			(effects
				(font
					(size 1.27 1.27)
				)
				(justify left)
				(hide yes)
			)
		)
		(property "IMax" "3.2 A"
			(at 265.43 113.03 0)
			(effects
				(font
					(size 1.27 1.27)
					(thickness 0.15)
				)
				(justify left bottom)
				(hide yes)
			)
		)
		(property "Size" "2x1.2"
			(at 265.43 115.57 0)
			(effects
				(font
					(size 1.27 1.27)
					(thickness 0.15)
				)
				(justify left bottom)
				(hide yes)
			)
		)
		(property "Author" "Antmicro"
			(at 265.43 118.11 0)
			(effects
				(font
					(size 1.27 1.27)
					(thickness 0.15)
				)
				(justify left bottom)
				(hide yes)
			)
		)
		(property "License" "Apache-2.0"
			(at 265.43 120.65 0)
			(effects
				(font
					(size 1.27 1.27)
					(thickness 0.15)
				)
				(justify left bottom)
				(hide yes)
			)
		)
		(property "Public" ""
			(at 265.43 123.19 0)
			(effects
				(font
					(size 1.27 1.27)
				)
				(justify left bottom)
				(hide yes)
			)
		)
		(pin "1"
		)
		(pin "2"
		)
		(instances
			(project "polarfire-som"
				(path ""
					(reference "L4")
					(unit 1)
				)
			)
		)
	)
	(symbol
		(lib_id "antmicroTestPoints:TP_0.75mm_SMD")
		(at 157.48 143.51 0)
		(unit 1)
		(exclude_from_sim no)
		(in_bom no)
		(on_board yes)
		(dnp no)
		(property "Reference" "TP23"
			(at 164.465 143.51 0)
			(effects
				(font
					(size 1.27 1.27)
					(thickness 0.15)
				)
			)
		)
		(property "Value" "TP_0.75mm_SMD"
			(at 168.275 147.32 0)
			(effects
				(font
					(size 1.27 1.27)
					(thickness 0.15)
				)
				(justify left bottom)
				(hide yes)
			)
		)
		(property "Footprint" "antmicro-footprints:TP_SMD_0.75mm"
			(at 168.275 149.86 0)
			(effects
				(font
					(size 1.27 1.27)
					(thickness 0.15)
				)
				(justify left bottom)
				(hide yes)
			)
		)
		(property "Datasheet" ""
			(at 175.26 156.21 0)
			(effects
				(font
					(size 1.27 1.27)
					(thickness 0.15)
				)
				(justify left bottom)
				(hide yes)
			)
		)
		(property "Description" "SMT test point"
			(at 157.48 143.51 0)
			(effects
				(font
					(size 1.27 1.27)
				)
				(hide yes)
			)
		)
		(property "MPN" ""
			(at 168.275 154.94 0)
			(effects
				(font
					(size 1.27 1.27)
					(thickness 0.15)
				)
				(justify left bottom)
				(hide yes)
			)
		)
		(property "Manufacturer" ""
			(at 168.275 149.86 0)
			(effects
				(font
					(size 1.27 1.27)
					(thickness 0.15)
				)
				(justify left bottom)
				(hide yes)
			)
		)
		(property "Author" "Antmicro"
			(at 168.275 152.4 0)
			(effects
				(font
					(size 1.27 1.27)
					(thickness 0.15)
				)
				(justify left bottom)
				(hide yes)
			)
		)
		(property "License" "Apache-2.0"
			(at 168.275 154.94 0)
			(effects
				(font
					(size 1.27 1.27)
					(thickness 0.15)
				)
				(justify left bottom)
				(hide yes)
			)
		)
		(property "Public" "False"
			(at 167.64 157.48 0)
			(effects
				(font
					(size 1.27 1.27)
				)
				(justify left bottom)
				(hide yes)
			)
		)
		(pin "1"
		)
		(instances
			(project "polarfire-som"
				(path ""
					(reference "TP23")
					(unit 1)
				)
			)
		)
	)
	(symbol
		(lib_id "antmicropower:GND")
		(at 63.5 72.39 0)
		(unit 1)
		(exclude_from_sim no)
		(in_bom yes)
		(on_board yes)
		(dnp no)
		(property "Reference" "#PWR074"
			(at 72.39 74.93 0)
			(effects
				(font
					(size 1.27 1.27)
					(thickness 0.15)
				)
				(justify left bottom)
				(hide yes)
			)
		)
		(property "Value" "GND"
			(at 63.5 76.2 0)
			(effects
				(font
					(size 1.27 1.27)
					(thickness 0.15)
				)
			)
		)
		(property "Footprint" ""
			(at 72.39 80.01 0)
			(effects
				(font
					(size 1.27 1.27)
					(thickness 0.15)
				)
				(justify left bottom)
				(hide yes)
			)
		)
		(property "Datasheet" ""
			(at 72.39 85.09 0)
			(effects
				(font
					(size 1.27 1.27)
					(thickness 0.15)
				)
				(justify left bottom)
				(hide yes)
			)
		)
		(property "Description" ""
			(at 63.5 72.39 0)
			(effects
				(font
					(size 1.27 1.27)
				)
				(hide yes)
			)
		)
		(property "Author" "Antmicro"
			(at 72.39 80.01 0)
			(effects
				(font
					(size 1.27 1.27)
					(thickness 0.15)
				)
				(justify left bottom)
				(hide yes)
			)
		)
		(property "License" "Apache-2.0"
			(at 72.39 82.55 0)
			(effects
				(font
					(size 1.27 1.27)
					(thickness 0.15)
				)
				(justify left bottom)
				(hide yes)
			)
		)
		(pin "1"
		)
		(instances
			(project "polarfire-som"
				(path ""
					(reference "#PWR074")
					(unit 1)
				)
			)
		)
	)
	(symbol
		(lib_id "antmicropower:GND")
		(at 271.78 100.33 0)
		(unit 1)
		(exclude_from_sim no)
		(in_bom yes)
		(on_board yes)
		(dnp no)
		(fields_autoplaced yes)
		(property "Reference" "#PWR0106"
			(at 280.67 102.87 0)
			(effects
				(font
					(size 1.27 1.27)
					(thickness 0.15)
				)
				(justify left bottom)
				(hide yes)
			)
		)
		(property "Value" "GND"
			(at 271.78 105.41 0)
			(effects
				(font
					(size 1.27 1.27)
					(thickness 0.15)
				)
			)
		)
		(property "Footprint" ""
			(at 280.67 107.95 0)
			(effects
				(font
					(size 1.27 1.27)
					(thickness 0.15)
				)
				(justify left bottom)
				(hide yes)
			)
		)
		(property "Datasheet" ""
			(at 280.67 113.03 0)
			(effects
				(font
					(size 1.27 1.27)
					(thickness 0.15)
				)
				(justify left bottom)
				(hide yes)
			)
		)
		(property "Description" ""
			(at 271.78 100.33 0)
			(effects
				(font
					(size 1.27 1.27)
				)
				(hide yes)
			)
		)
		(property "Author" "Antmicro"
			(at 280.67 107.95 0)
			(effects
				(font
					(size 1.27 1.27)
					(thickness 0.15)
				)
				(justify left bottom)
				(hide yes)
			)
		)
		(property "License" "Apache-2.0"
			(at 280.67 110.49 0)
			(effects
				(font
					(size 1.27 1.27)
					(thickness 0.15)
				)
				(justify left bottom)
				(hide yes)
			)
		)
		(pin "1"
		)
		(instances
			(project "polarfire-som"
				(path ""
					(reference "#PWR0106")
					(unit 1)
				)
			)
		)
	)
	(symbol
		(lib_id "antmicropower:+1V1")
		(at 299.72 59.69 0)
		(unit 1)
		(exclude_from_sim no)
		(in_bom yes)
		(on_board yes)
		(dnp no)
		(property "Reference" "#PWR0111"
			(at 299.72 63.5 0)
			(effects
				(font
					(size 1.27 1.27)
				)
				(hide yes)
			)
		)
		(property "Value" "+1V1"
			(at 299.72 55.245 0)
			(effects
				(font
					(size 1.27 1.27)
				)
			)
		)
		(property "Footprint" ""
			(at 299.72 59.69 0)
			(effects
				(font
					(size 1.27 1.27)
				)
				(hide yes)
			)
		)
		(property "Datasheet" ""
			(at 299.72 59.69 0)
			(effects
				(font
					(size 1.27 1.27)
				)
				(hide yes)
			)
		)
		(property "Description" ""
			(at 299.72 59.69 0)
			(effects
				(font
					(size 1.27 1.27)
				)
				(hide yes)
			)
		)
		(pin "1"
		)
		(instances
			(project "polarfire-som"
				(path ""
					(reference "#PWR0111")
					(unit 1)
				)
			)
		)
	)
	(symbol
		(lib_id "antmicropower:VDDI")
		(at 33.02 53.34 0)
		(unit 1)
		(exclude_from_sim no)
		(in_bom yes)
		(on_board yes)
		(dnp no)
		(fields_autoplaced yes)
		(property "Reference" "#PWR0319"
			(at 33.02 57.15 0)
			(effects
				(font
					(size 1.27 1.27)
				)
				(hide yes)
			)
		)
		(property "Value" "VDD"
			(at 33.02 48.895 0)
			(effects
				(font
					(size 1.27 1.27)
				)
			)
		)
		(property "Footprint" ""
			(at 33.02 53.34 0)
			(effects
				(font
					(size 1.27 1.27)
				)
				(hide yes)
			)
		)
		(property "Datasheet" ""
			(at 33.02 53.34 0)
			(effects
				(font
					(size 1.27 1.27)
				)
				(hide yes)
			)
		)
		(property "Description" ""
			(at 33.02 53.34 0)
			(effects
				(font
					(size 1.27 1.27)
				)
				(hide yes)
			)
		)
		(pin "1"
		)
		(instances
			(project "polarfire-som"
				(path ""
					(reference "#PWR0319")
					(unit 1)
				)
			)
		)
	)
	(symbol
		(lib_id "antmicropower:PWR_FLAG")
		(at 306.07 116.84 270)
		(unit 1)
		(exclude_from_sim no)
		(in_bom yes)
		(on_board yes)
		(dnp no)
		(property "Reference" "#FLG026"
			(at 307.975 116.84 0)
			(effects
				(font
					(size 1.27 1.27)
				)
				(hide yes)
			)
		)
		(property "Value" "PWR_FLAG"
			(at 313.944 116.84 90)
			(effects
				(font
					(size 1.27 1.27)
				)
			)
		)
		(property "Footprint" ""
			(at 306.07 116.84 0)
			(effects
				(font
					(size 1.27 1.27)
				)
				(hide yes)
			)
		)
		(property "Datasheet" ""
			(at 306.07 116.84 0)
			(effects
				(font
					(size 1.27 1.27)
				)
				(hide yes)
			)
		)
		(property "Description" ""
			(at 306.07 116.84 0)
			(effects
				(font
					(size 1.27 1.27)
				)
				(hide yes)
			)
		)
		(pin "1"
		)
		(instances
			(project "polarfire-som"
				(path ""
					(reference "#FLG026")
					(unit 1)
				)
			)
		)
	)
	(symbol
		(lib_id "antmicroResistors0402:R_590R_0402")
		(at 365.76 127 90)
		(unit 1)
		(exclude_from_sim no)
		(in_bom yes)
		(on_board yes)
		(dnp no)
		(fields_autoplaced yes)
		(property "Reference" "R68"
			(at 368.3 123.19 90)
			(effects
				(font
					(size 1.27 1.27)
					(thickness 0.15)
				)
				(justify right)
			)
		)
		(property "Value" "R_590R_0402"
			(at 378.46 106.68 0)
			(effects
				(font
					(size 1.27 1.27)
					(thickness 0.15)
				)
				(justify left bottom)
				(hide yes)
			)
		)
		(property "Footprint" "antmicro-footprints:R_0402_1005Metric"
			(at 381 106.68 0)
			(effects
				(font
					(size 1.27 1.27)
					(thickness 0.15)
				)
				(justify left bottom)
				(hide yes)
			)
		)
		(property "Datasheet" "https://www.bourns.com/docs/product-datasheets/cr.pdf"
			(at 383.54 106.68 0)
			(effects
				(font
					(size 1.27 1.27)
					(thickness 0.15)
				)
				(justify left bottom)
				(hide yes)
			)
		)
		(property "Description" "SMD Chip Resistor, 590 ohm, ± 1%, 100 mW, 0402 [1005 Metric], Thick Film, Precision"
			(at 365.76 127 0)
			(effects
				(font
					(size 1.27 1.27)
				)
				(hide yes)
			)
		)
		(property "MPN" "CR0402-FX-5900GLF"
			(at 386.08 106.68 0)
			(effects
				(font
					(size 1.27 1.27)
					(thickness 0.15)
				)
				(justify left bottom)
				(hide yes)
			)
		)
		(property "Manufacturer" "Bourns"
			(at 388.62 106.68 0)
			(effects
				(font
					(size 1.27 1.27)
					(thickness 0.15)
				)
				(justify left bottom)
				(hide yes)
			)
		)
		(property "License" "Apache-2.0"
			(at 391.16 106.68 0)
			(effects
				(font
					(size 1.27 1.27)
					(thickness 0.15)
				)
				(justify left bottom)
				(hide yes)
			)
		)
		(property "Author" "Antmicro"
			(at 393.7 106.68 0)
			(effects
				(font
					(size 1.27 1.27)
					(thickness 0.15)
				)
				(justify left bottom)
				(hide yes)
			)
		)
		(property "Val" "590R"
			(at 368.3 125.73 90)
			(effects
				(font
					(size 1.27 1.27)
					(thickness 0.15)
				)
				(justify right)
			)
		)
		(property "Tolerance" "1%"
			(at 375.92 106.68 0)
			(effects
				(font
					(size 1.27 1.27)
				)
				(justify left bottom)
				(hide yes)
			)
		)
		(property "Public" ""
			(at 396.24 106.68 0)
			(effects
				(font
					(size 1.27 1.27)
				)
				(justify left bottom)
				(hide yes)
			)
		)
		(pin "1"
		)
		(pin "2"
		)
		(instances
			(project "polarfire-som"
				(path ""
					(reference "R68")
					(unit 1)
				)
			)
		)
	)
	(symbol
		(lib_id "antmicropower:GND")
		(at 365.76 153.67 0)
		(unit 1)
		(exclude_from_sim no)
		(in_bom yes)
		(on_board yes)
		(dnp no)
		(property "Reference" "#PWR0278"
			(at 374.65 156.21 0)
			(effects
				(font
					(size 1.27 1.27)
					(thickness 0.15)
				)
				(justify left bottom)
				(hide yes)
			)
		)
		(property "Value" "GND"
			(at 365.76 158.75 0)
			(effects
				(font
					(size 1.27 1.27)
					(thickness 0.15)
				)
			)
		)
		(property "Footprint" ""
			(at 374.65 161.29 0)
			(effects
				(font
					(size 1.27 1.27)
					(thickness 0.15)
				)
				(justify left bottom)
				(hide yes)
			)
		)
		(property "Datasheet" ""
			(at 374.65 166.37 0)
			(effects
				(font
					(size 1.27 1.27)
					(thickness 0.15)
				)
				(justify left bottom)
				(hide yes)
			)
		)
		(property "Description" ""
			(at 365.76 153.67 0)
			(effects
				(font
					(size 1.27 1.27)
				)
				(hide yes)
			)
		)
		(property "Author" "Antmicro"
			(at 374.65 161.29 0)
			(effects
				(font
					(size 1.27 1.27)
					(thickness 0.15)
				)
				(justify left bottom)
				(hide yes)
			)
		)
		(property "License" "Apache-2.0"
			(at 374.65 163.83 0)
			(effects
				(font
					(size 1.27 1.27)
					(thickness 0.15)
				)
				(justify left bottom)
				(hide yes)
			)
		)
		(pin "1"
		)
		(instances
			(project "polarfire-som"
				(path ""
					(reference "#PWR0278")
					(unit 1)
				)
			)
		)
	)
	(symbol
		(lib_id "antmicroCapacitors0402:C_22u_0402")
		(at 198.12 215.9 90)
		(unit 1)
		(exclude_from_sim no)
		(in_bom yes)
		(on_board yes)
		(dnp no)
		(fields_autoplaced yes)
		(property "Reference" "C91"
			(at 200.66 212.0836 90)
			(effects
				(font
					(size 1.27 1.27)
					(thickness 0.15)
				)
				(justify right)
			)
		)
		(property "Value" "C_22u_0402"
			(at 208.28 195.58 0)
			(effects
				(font
					(size 1.27 1.27)
					(thickness 0.15)
				)
				(justify left bottom)
				(hide yes)
			)
		)
		(property "Footprint" "antmicro-footprints:C_0402_1005Metric"
			(at 210.82 195.58 0)
			(effects
				(font
					(size 1.27 1.27)
					(thickness 0.15)
				)
				(justify left bottom)
				(hide yes)
			)
		)
		(property "Datasheet" "https://www.murata.com/products/productdetail?partno=GRM158R60J226ME01%23"
			(at 213.36 195.58 0)
			(effects
				(font
					(size 1.27 1.27)
					(thickness 0.15)
				)
				(justify left bottom)
				(hide yes)
			)
		)
		(property "Description" "SMD Multilayer Ceramic Capacitor, 22 uF, 4 V, 0402 [1005 Metric], X6S"
			(at 198.12 215.9 0)
			(effects
				(font
					(size 1.27 1.27)
				)
				(hide yes)
			)
		)
		(property "MPN" "GRM158R60J226ME01D"
			(at 215.9 195.58 0)
			(effects
				(font
					(size 1.27 1.27)
					(thickness 0.15)
				)
				(justify left bottom)
				(hide yes)
			)
		)
		(property "Manufacturer" "Murata"
			(at 218.44 195.58 0)
			(effects
				(font
					(size 1.27 1.27)
					(thickness 0.15)
				)
				(justify left bottom)
				(hide yes)
			)
		)
		(property "License" "Apache-2.0"
			(at 220.98 195.58 0)
			(effects
				(font
					(size 1.27 1.27)
					(thickness 0.15)
				)
				(justify left bottom)
				(hide yes)
			)
		)
		(property "Author" "Antmicro"
			(at 223.52 195.58 0)
			(effects
				(font
					(size 1.27 1.27)
					(thickness 0.15)
				)
				(justify left bottom)
				(hide yes)
			)
		)
		(property "Val" "22u"
			(at 200.66 214.6236 90)
			(effects
				(font
					(size 1.27 1.27)
					(thickness 0.15)
				)
				(justify right)
			)
		)
		(property "Voltage" ""
			(at 226.06 195.58 0)
			(effects
				(font
					(size 1.27 1.27)
				)
				(justify left bottom)
				(hide yes)
			)
		)
		(property "Dielectric" ""
			(at 228.6 195.58 0)
			(effects
				(font
					(size 1.27 1.27)
				)
				(justify left bottom)
				(hide yes)
			)
		)
		(property "Public" ""
			(at 231.14 195.58 0)
			(effects
				(font
					(size 1.27 1.27)
				)
				(justify left bottom)
				(hide yes)
			)
		)
		(pin "2"
		)
		(pin "1"
		)
		(instances
			(project "polarfire-som"
				(path ""
					(reference "C91")
					(unit 1)
				)
			)
		)
	)
	(symbol
		(lib_id "antmicroResistors0402:R_93k1_0402")
		(at 290.83 237.49 90)
		(unit 1)
		(exclude_from_sim no)
		(in_bom yes)
		(on_board yes)
		(dnp no)
		(fields_autoplaced yes)
		(property "Reference" "R64"
			(at 293.37 233.68 90)
			(effects
				(font
					(size 1.27 1.27)
					(thickness 0.15)
				)
				(justify right)
			)
		)
		(property "Value" "R_93k1_0402"
			(at 303.53 217.17 0)
			(effects
				(font
					(size 1.27 1.27)
					(thickness 0.15)
				)
				(justify left bottom)
				(hide yes)
			)
		)
		(property "Footprint" "antmicro-footprints:R_0402_1005Metric"
			(at 306.07 217.17 0)
			(effects
				(font
					(size 1.27 1.27)
					(thickness 0.15)
				)
				(justify left bottom)
				(hide yes)
			)
		)
		(property "Datasheet" "https://www.bourns.com/docs/product-datasheets/cr.pdf"
			(at 308.61 217.17 0)
			(effects
				(font
					(size 1.27 1.27)
					(thickness 0.15)
				)
				(justify left bottom)
				(hide yes)
			)
		)
		(property "Description" "SMD Chip Resistor"
			(at 290.83 237.49 0)
			(effects
				(font
					(size 1.27 1.27)
				)
				(hide yes)
			)
		)
		(property "MPN" "CR0402-FX-9312GLF"
			(at 311.15 217.17 0)
			(effects
				(font
					(size 1.27 1.27)
					(thickness 0.15)
				)
				(justify left bottom)
				(hide yes)
			)
		)
		(property "Manufacturer" "Bourns"
			(at 313.69 217.17 0)
			(effects
				(font
					(size 1.27 1.27)
					(thickness 0.15)
				)
				(justify left bottom)
				(hide yes)
			)
		)
		(property "License" "Apache-2.0"
			(at 316.23 217.17 0)
			(effects
				(font
					(size 1.27 1.27)
					(thickness 0.15)
				)
				(justify left bottom)
				(hide yes)
			)
		)
		(property "Author" "Antmicro"
			(at 318.77 217.17 0)
			(effects
				(font
					(size 1.27 1.27)
					(thickness 0.15)
				)
				(justify left bottom)
				(hide yes)
			)
		)
		(property "Val" "93k1"
			(at 293.37 236.22 90)
			(effects
				(font
					(size 1.27 1.27)
					(thickness 0.15)
				)
				(justify right)
			)
		)
		(property "Tolerance" "1%"
			(at 300.99 217.17 0)
			(effects
				(font
					(size 1.27 1.27)
				)
				(justify left bottom)
				(hide yes)
			)
		)
		(property "Public" ""
			(at 321.31 217.17 0)
			(effects
				(font
					(size 1.27 1.27)
				)
				(justify left bottom)
				(hide yes)
			)
		)
		(pin "2"
		)
		(pin "1"
		)
		(instances
			(project "polarfire-som"
				(path ""
					(reference "R64")
					(unit 1)
				)
			)
		)
	)
	(symbol
		(lib_id "antmicropower:+5V")
		(at 165.1 67.31 0)
		(unit 1)
		(exclude_from_sim no)
		(in_bom yes)
		(on_board yes)
		(dnp no)
		(fields_autoplaced yes)
		(property "Reference" "#PWR083"
			(at 180.34 69.85 0)
			(effects
				(font
					(size 1.27 1.27)
					(thickness 0.15)
				)
				(justify left bottom)
				(hide yes)
			)
		)
		(property "Value" "+5V"
			(at 165.1 62.23 0)
			(effects
				(font
					(size 1.27 1.27)
					(thickness 0.15)
				)
			)
		)
		(property "Footprint" ""
			(at 180.34 74.93 0)
			(effects
				(font
					(size 1.27 1.27)
					(thickness 0.15)
				)
				(justify left bottom)
				(hide yes)
			)
		)
		(property "Datasheet" ""
			(at 180.34 77.47 0)
			(effects
				(font
					(size 1.27 1.27)
					(thickness 0.15)
				)
				(justify left bottom)
				(hide yes)
			)
		)
		(property "Description" ""
			(at 165.1 67.31 0)
			(effects
				(font
					(size 1.27 1.27)
				)
				(hide yes)
			)
		)
		(property "Author" "Antmicro"
			(at 180.34 74.93 0)
			(effects
				(font
					(size 1.27 1.27)
					(thickness 0.15)
				)
				(justify left bottom)
				(hide yes)
			)
		)
		(property "License" "Apache-2.0"
			(at 180.34 77.47 0)
			(effects
				(font
					(size 1.27 1.27)
					(thickness 0.15)
				)
				(justify left bottom)
				(hide yes)
			)
		)
		(pin "1"
		)
		(instances
			(project "polarfire-som"
				(path ""
					(reference "#PWR083")
					(unit 1)
				)
			)
		)
	)
	(symbol
		(lib_id "antmicroTransistorsFETsMOSFETsSingle:DMG1012T-7")
		(at 359.41 144.78 0)
		(unit 1)
		(exclude_from_sim no)
		(in_bom yes)
		(on_board yes)
		(dnp no)
		(fields_autoplaced yes)
		(property "Reference" "Q6"
			(at 369.57 140.97 0)
			(effects
				(font
					(size 1.27 1.27)
					(thickness 0.15)
				)
				(justify left)
			)
		)
		(property "Value" "DMG1012T-7"
			(at 369.57 148.59 0)
			(effects
				(font
					(size 1.27 1.27)
					(thickness 0.15)
				)
				(justify left bottom)
				(hide yes)
			)
		)
		(property "Footprint" "antmicro-footprints:SOT-523"
			(at 369.57 151.13 0)
			(effects
				(font
					(size 1.27 1.27)
					(thickness 0.15)
				)
				(justify left bottom)
				(hide yes)
			)
		)
		(property "Datasheet" "https://www.diodes.com/assets/Datasheets/ds31783.pdf"
			(at 369.57 153.67 0)
			(effects
				(font
					(size 1.27 1.27)
					(thickness 0.15)
				)
				(justify left bottom)
				(hide yes)
			)
		)
		(property "Description" "Power MOSFET, N Channel, 20 V, 630 mA, 0.3 ohm, SOT-523, Surface Mount"
			(at 359.41 144.78 0)
			(effects
				(font
					(size 1.27 1.27)
				)
				(hide yes)
			)
		)
		(property "MPN" "DMG1012T-7"
			(at 369.57 143.51 0)
			(effects
				(font
					(size 1.27 1.27)
					(thickness 0.15)
				)
				(justify left)
			)
		)
		(property "Manufacturer" "Diodes Incorporated"
			(at 369.57 146.05 0)
			(effects
				(font
					(size 1.27 1.27)
					(thickness 0.15)
				)
				(justify left bottom)
				(hide yes)
			)
		)
		(property "Author" "Antmicro"
			(at 369.57 156.21 0)
			(effects
				(font
					(size 1.27 1.27)
					(thickness 0.15)
				)
				(justify left bottom)
				(hide yes)
			)
		)
		(property "License" "Apache-2.0"
			(at 369.57 158.75 0)
			(effects
				(font
					(size 1.27 1.27)
					(thickness 0.15)
				)
				(justify left bottom)
				(hide yes)
			)
		)
		(property "Public" ""
			(at 379.73 152.4 0)
			(effects
				(font
					(size 1.27 1.27)
				)
				(justify left bottom)
				(hide yes)
			)
		)
		(pin "1"
		)
		(pin "2"
		)
		(pin "3"
		)
		(instances
			(project "polarfire-som"
				(path ""
					(reference "Q6")
					(unit 1)
				)
			)
		)
	)
	(symbol
		(lib_id "antmicroTestPoints:TP_0.75mm_SMD")
		(at 278.13 58.42 0)
		(unit 1)
		(exclude_from_sim no)
		(in_bom no)
		(on_board yes)
		(dnp no)
		(property "Reference" "TP5"
			(at 285.115 58.42 0)
			(effects
				(font
					(size 1.27 1.27)
					(thickness 0.15)
				)
			)
		)
		(property "Value" "TP_0.75mm_SMD"
			(at 288.925 62.23 0)
			(effects
				(font
					(size 1.27 1.27)
					(thickness 0.15)
				)
				(justify left bottom)
				(hide yes)
			)
		)
		(property "Footprint" "antmicro-footprints:TP_SMD_0.75mm"
			(at 288.925 64.77 0)
			(effects
				(font
					(size 1.27 1.27)
					(thickness 0.15)
				)
				(justify left bottom)
				(hide yes)
			)
		)
		(property "Datasheet" ""
			(at 295.91 71.12 0)
			(effects
				(font
					(size 1.27 1.27)
					(thickness 0.15)
				)
				(justify left bottom)
				(hide yes)
			)
		)
		(property "Description" "SMT test point"
			(at 278.13 58.42 0)
			(effects
				(font
					(size 1.27 1.27)
				)
				(hide yes)
			)
		)
		(property "MPN" ""
			(at 288.925 69.85 0)
			(effects
				(font
					(size 1.27 1.27)
					(thickness 0.15)
				)
				(justify left bottom)
				(hide yes)
			)
		)
		(property "Manufacturer" ""
			(at 288.925 64.77 0)
			(effects
				(font
					(size 1.27 1.27)
					(thickness 0.15)
				)
				(justify left bottom)
				(hide yes)
			)
		)
		(property "Author" "Antmicro"
			(at 288.925 67.31 0)
			(effects
				(font
					(size 1.27 1.27)
					(thickness 0.15)
				)
				(justify left bottom)
				(hide yes)
			)
		)
		(property "License" "Apache-2.0"
			(at 288.925 69.85 0)
			(effects
				(font
					(size 1.27 1.27)
					(thickness 0.15)
				)
				(justify left bottom)
				(hide yes)
			)
		)
		(property "Public" "False"
			(at 288.29 72.39 0)
			(effects
				(font
					(size 1.27 1.27)
				)
				(justify left bottom)
				(hide yes)
			)
		)
		(pin "1"
		)
		(instances
			(project "polarfire-som"
				(path ""
					(reference "TP5")
					(unit 1)
				)
			)
		)
	)
	(symbol
		(lib_id "antmicropower:GND")
		(at 33.02 60.96 0)
		(unit 1)
		(exclude_from_sim no)
		(in_bom yes)
		(on_board yes)
		(dnp no)
		(property "Reference" "#PWR064"
			(at 41.91 63.5 0)
			(effects
				(font
					(size 1.27 1.27)
					(thickness 0.15)
				)
				(justify left bottom)
				(hide yes)
			)
		)
		(property "Value" "GND"
			(at 33.02 64.77 0)
			(effects
				(font
					(size 1.27 1.27)
					(thickness 0.15)
				)
			)
		)
		(property "Footprint" ""
			(at 41.91 68.58 0)
			(effects
				(font
					(size 1.27 1.27)
					(thickness 0.15)
				)
				(justify left bottom)
				(hide yes)
			)
		)
		(property "Datasheet" ""
			(at 41.91 73.66 0)
			(effects
				(font
					(size 1.27 1.27)
					(thickness 0.15)
				)
				(justify left bottom)
				(hide yes)
			)
		)
		(property "Description" ""
			(at 33.02 60.96 0)
			(effects
				(font
					(size 1.27 1.27)
				)
				(hide yes)
			)
		)
		(property "Author" "Antmicro"
			(at 41.91 68.58 0)
			(effects
				(font
					(size 1.27 1.27)
					(thickness 0.15)
				)
				(justify left bottom)
				(hide yes)
			)
		)
		(property "License" "Apache-2.0"
			(at 41.91 71.12 0)
			(effects
				(font
					(size 1.27 1.27)
					(thickness 0.15)
				)
				(justify left bottom)
				(hide yes)
			)
		)
		(pin "1"
		)
		(instances
			(project "polarfire-som"
				(path ""
					(reference "#PWR064")
					(unit 1)
				)
			)
		)
	)
	(symbol
		(lib_id "antmicropower:GND")
		(at 182.88 76.2 0)
		(unit 1)
		(exclude_from_sim no)
		(in_bom yes)
		(on_board yes)
		(dnp no)
		(fields_autoplaced yes)
		(property "Reference" "#PWR087"
			(at 191.77 78.74 0)
			(effects
				(font
					(size 1.27 1.27)
					(thickness 0.15)
				)
				(justify left bottom)
				(hide yes)
			)
		)
		(property "Value" "GND"
			(at 182.88 81.28 0)
			(effects
				(font
					(size 1.27 1.27)
					(thickness 0.15)
				)
			)
		)
		(property "Footprint" ""
			(at 191.77 83.82 0)
			(effects
				(font
					(size 1.27 1.27)
					(thickness 0.15)
				)
				(justify left bottom)
				(hide yes)
			)
		)
		(property "Datasheet" ""
			(at 191.77 88.9 0)
			(effects
				(font
					(size 1.27 1.27)
					(thickness 0.15)
				)
				(justify left bottom)
				(hide yes)
			)
		)
		(property "Description" ""
			(at 182.88 76.2 0)
			(effects
				(font
					(size 1.27 1.27)
				)
				(hide yes)
			)
		)
		(property "Author" "Antmicro"
			(at 191.77 83.82 0)
			(effects
				(font
					(size 1.27 1.27)
					(thickness 0.15)
				)
				(justify left bottom)
				(hide yes)
			)
		)
		(property "License" "Apache-2.0"
			(at 191.77 86.36 0)
			(effects
				(font
					(size 1.27 1.27)
					(thickness 0.15)
				)
				(justify left bottom)
				(hide yes)
			)
		)
		(pin "1"
		)
		(instances
			(project "polarfire-som"
				(path ""
					(reference "#PWR087")
					(unit 1)
				)
			)
		)
	)
	(symbol
		(lib_id "antmicroResistors0402:R_10k_0402")
		(at 260.35 234.95 0)
		(unit 1)
		(exclude_from_sim no)
		(in_bom yes)
		(on_board yes)
		(dnp no)
		(fields_autoplaced yes)
		(property "Reference" "R16"
			(at 262.89 238.125 0)
			(effects
				(font
					(size 1.27 1.27)
					(thickness 0.15)
				)
			)
		)
		(property "Value" "R_10k_0402"
			(at 280.67 247.65 0)
			(effects
				(font
					(size 1.27 1.27)
					(thickness 0.15)
				)
				(justify left bottom)
				(hide yes)
			)
		)
		(property "Footprint" "antmicro-footprints:R_0402_1005Metric"
			(at 280.67 250.19 0)
			(effects
				(font
					(size 1.27 1.27)
					(thickness 0.15)
				)
				(justify left bottom)
				(hide yes)
			)
		)
		(property "Datasheet" "https://www.bourns.com/docs/product-datasheets/cr.pdf"
			(at 280.67 252.73 0)
			(effects
				(font
					(size 1.27 1.27)
					(thickness 0.15)
				)
				(justify left bottom)
				(hide yes)
			)
		)
		(property "Description" "SMD Chip Resistor, 10 kohm, ± 1%, 62.5 mW, 0402 [1005 Metric], Thick Film, General Purpose"
			(at 260.35 234.95 0)
			(effects
				(font
					(size 1.27 1.27)
				)
				(hide yes)
			)
		)
		(property "MPN" "CR0402-FX-1002GLF"
			(at 280.67 255.27 0)
			(effects
				(font
					(size 1.27 1.27)
					(thickness 0.15)
				)
				(justify left bottom)
				(hide yes)
			)
		)
		(property "Manufacturer" "Bourns"
			(at 280.67 257.81 0)
			(effects
				(font
					(size 1.27 1.27)
					(thickness 0.15)
				)
				(justify left bottom)
				(hide yes)
			)
		)
		(property "License" "Apache-2.0"
			(at 280.67 260.35 0)
			(effects
				(font
					(size 1.27 1.27)
					(thickness 0.15)
				)
				(justify left bottom)
				(hide yes)
			)
		)
		(property "Author" "Antmicro"
			(at 280.67 262.89 0)
			(effects
				(font
					(size 1.27 1.27)
					(thickness 0.15)
				)
				(justify left bottom)
				(hide yes)
			)
		)
		(property "Val" "10k"
			(at 262.89 240.665 0)
			(effects
				(font
					(size 1.27 1.27)
					(thickness 0.15)
				)
			)
		)
		(property "Tolerance" "1%"
			(at 280.67 245.11 0)
			(effects
				(font
					(size 1.27 1.27)
				)
				(justify left bottom)
				(hide yes)
			)
		)
		(property "Public" ""
			(at 280.67 265.43 0)
			(effects
				(font
					(size 1.27 1.27)
				)
				(justify left bottom)
				(hide yes)
			)
		)
		(pin "2"
		)
		(pin "1"
		)
		(instances
			(project "polarfire-som"
				(path ""
					(reference "R16")
					(unit 1)
				)
			)
		)
	)
	(symbol
		(lib_id "antmicroCapacitors0402:C_22u_0402")
		(at 271.78 99.06 90)
		(unit 1)
		(exclude_from_sim no)
		(in_bom yes)
		(on_board yes)
		(dnp no)
		(fields_autoplaced yes)
		(property "Reference" "C108"
			(at 274.32 95.2436 90)
			(effects
				(font
					(size 1.27 1.27)
					(thickness 0.15)
				)
				(justify right)
			)
		)
		(property "Value" "C_22u_0402"
			(at 281.94 78.74 0)
			(effects
				(font
					(size 1.27 1.27)
					(thickness 0.15)
				)
				(justify left bottom)
				(hide yes)
			)
		)
		(property "Footprint" "antmicro-footprints:C_0402_1005Metric"
			(at 284.48 78.74 0)
			(effects
				(font
					(size 1.27 1.27)
					(thickness 0.15)
				)
				(justify left bottom)
				(hide yes)
			)
		)
		(property "Datasheet" "https://www.murata.com/products/productdetail?partno=GRM158R60J226ME01%23"
			(at 287.02 78.74 0)
			(effects
				(font
					(size 1.27 1.27)
					(thickness 0.15)
				)
				(justify left bottom)
				(hide yes)
			)
		)
		(property "Description" "SMD Multilayer Ceramic Capacitor, 22 uF, 4 V, 0402 [1005 Metric], X6S"
			(at 271.78 99.06 0)
			(effects
				(font
					(size 1.27 1.27)
				)
				(hide yes)
			)
		)
		(property "MPN" "GRM158R60J226ME01D"
			(at 289.56 78.74 0)
			(effects
				(font
					(size 1.27 1.27)
					(thickness 0.15)
				)
				(justify left bottom)
				(hide yes)
			)
		)
		(property "Manufacturer" "Murata"
			(at 292.1 78.74 0)
			(effects
				(font
					(size 1.27 1.27)
					(thickness 0.15)
				)
				(justify left bottom)
				(hide yes)
			)
		)
		(property "License" "Apache-2.0"
			(at 294.64 78.74 0)
			(effects
				(font
					(size 1.27 1.27)
					(thickness 0.15)
				)
				(justify left bottom)
				(hide yes)
			)
		)
		(property "Author" "Antmicro"
			(at 297.18 78.74 0)
			(effects
				(font
					(size 1.27 1.27)
					(thickness 0.15)
				)
				(justify left bottom)
				(hide yes)
			)
		)
		(property "Val" "22u"
			(at 274.32 97.7836 90)
			(effects
				(font
					(size 1.27 1.27)
					(thickness 0.15)
				)
				(justify right)
			)
		)
		(property "Voltage" ""
			(at 299.72 78.74 0)
			(effects
				(font
					(size 1.27 1.27)
				)
				(justify left bottom)
				(hide yes)
			)
		)
		(property "Dielectric" ""
			(at 302.26 78.74 0)
			(effects
				(font
					(size 1.27 1.27)
				)
				(justify left bottom)
				(hide yes)
			)
		)
		(property "Public" ""
			(at 304.8 78.74 0)
			(effects
				(font
					(size 1.27 1.27)
				)
				(justify left bottom)
				(hide yes)
			)
		)
		(pin "2"
		)
		(pin "1"
		)
		(instances
			(project "polarfire-som"
				(path ""
					(reference "C108")
					(unit 1)
				)
			)
		)
	)
	(symbol
		(lib_id "antmicroFixedInductors:L_1u5_2.8A_0806")
		(at 251.46 110.49 0)
		(unit 1)
		(exclude_from_sim no)
		(in_bom yes)
		(on_board yes)
		(dnp no)
		(fields_autoplaced yes)
		(property "Reference" "L5"
			(at 254 105.41 0)
			(effects
				(font
					(size 1.27 1.27)
					(thickness 0.15)
				)
			)
		)
		(property "Value" "L_1u5_2.8A_0806"
			(at 265.43 113.03 0)
			(effects
				(font
					(size 1.27 1.27)
					(thickness 0.15)
				)
				(justify left bottom)
				(hide yes)
			)
		)
		(property "Footprint" "antmicro-footprints:L_0806_2016Metric"
			(at 265.43 118.11 0)
			(effects
				(font
					(size 1.27 1.27)
					(thickness 0.15)
				)
				(justify left bottom)
				(hide yes)
			)
		)
		(property "Datasheet" "https://abracon.com/datasheets/AOTA-B201610S.pdf"
			(at 265.43 120.65 0)
			(effects
				(font
					(size 1.27 1.27)
					(thickness 0.15)
				)
				(justify left bottom)
				(hide yes)
			)
		)
		(property "Description" "Power Inductor (SMT), 1.5 µH, 0.074 ohm, 2.8 A, AOTA-B201610S"
			(at 251.46 110.49 0)
			(effects
				(font
					(size 1.27 1.27)
				)
				(hide yes)
			)
		)
		(property "Val" "1.5u/2.8A"
			(at 254 107.95 0)
			(effects
				(font
					(size 1.27 1.27)
					(thickness 0.15)
				)
			)
		)
		(property "Manufacturer" "Abracon"
			(at 265.43 123.19 0)
			(effects
				(font
					(size 1.27 1.27)
					(thickness 0.15)
				)
				(justify left bottom)
				(hide yes)
			)
		)
		(property "MPN" "AOTA-B201610S1R5MT"
			(at 265.43 125.73 0)
			(effects
				(font
					(size 1.27 1.27)
					(thickness 0.15)
				)
				(justify left bottom)
				(hide yes)
			)
		)
		(property "ISat" "3.5 A"
			(at 265.43 127 0)
			(effects
				(font
					(size 1.27 1.27)
				)
				(justify left)
				(hide yes)
			)
		)
		(property "IMax" "2.8 A"
			(at 265.43 130.81 0)
			(effects
				(font
					(size 1.27 1.27)
					(thickness 0.15)
				)
				(justify left bottom)
				(hide yes)
			)
		)
		(property "Size" "2.0x1.6"
			(at 265.43 133.35 0)
			(effects
				(font
					(size 1.27 1.27)
					(thickness 0.15)
				)
				(justify left bottom)
				(hide yes)
			)
		)
		(property "Author" "Antmicro"
			(at 265.43 135.89 0)
			(effects
				(font
					(size 1.27 1.27)
					(thickness 0.15)
				)
				(justify left bottom)
				(hide yes)
			)
		)
		(property "License" "Apache-2.0"
			(at 265.43 138.43 0)
			(effects
				(font
					(size 1.27 1.27)
					(thickness 0.15)
				)
				(justify left bottom)
				(hide yes)
			)
		)
		(property "Public" ""
			(at 265.43 140.97 0)
			(effects
				(font
					(size 1.27 1.27)
				)
				(justify left bottom)
				(hide yes)
			)
		)
		(pin "1"
		)
		(pin "2"
		)
		(instances
			(project "polarfire-som"
				(path ""
					(reference "L5")
					(unit 1)
				)
			)
		)
	)
	(symbol
		(lib_id "antmicroCapacitors0402:C_22u_0402")
		(at 182.88 74.93 90)
		(unit 1)
		(exclude_from_sim no)
		(in_bom yes)
		(on_board yes)
		(dnp no)
		(fields_autoplaced yes)
		(property "Reference" "C87"
			(at 185.42 71.1136 90)
			(effects
				(font
					(size 1.27 1.27)
					(thickness 0.15)
				)
				(justify right)
			)
		)
		(property "Value" "C_22u_0402"
			(at 193.04 54.61 0)
			(effects
				(font
					(size 1.27 1.27)
					(thickness 0.15)
				)
				(justify left bottom)
				(hide yes)
			)
		)
		(property "Footprint" "antmicro-footprints:C_0402_1005Metric"
			(at 195.58 54.61 0)
			(effects
				(font
					(size 1.27 1.27)
					(thickness 0.15)
				)
				(justify left bottom)
				(hide yes)
			)
		)
		(property "Datasheet" "https://www.murata.com/products/productdetail?partno=GRM158R60J226ME01%23"
			(at 198.12 54.61 0)
			(effects
				(font
					(size 1.27 1.27)
					(thickness 0.15)
				)
				(justify left bottom)
				(hide yes)
			)
		)
		(property "Description" "SMD Multilayer Ceramic Capacitor, 22 uF, 4 V, 0402 [1005 Metric], X6S"
			(at 182.88 74.93 0)
			(effects
				(font
					(size 1.27 1.27)
				)
				(hide yes)
			)
		)
		(property "MPN" "GRM158R60J226ME01D"
			(at 200.66 54.61 0)
			(effects
				(font
					(size 1.27 1.27)
					(thickness 0.15)
				)
				(justify left bottom)
				(hide yes)
			)
		)
		(property "Manufacturer" "Murata"
			(at 203.2 54.61 0)
			(effects
				(font
					(size 1.27 1.27)
					(thickness 0.15)
				)
				(justify left bottom)
				(hide yes)
			)
		)
		(property "License" "Apache-2.0"
			(at 205.74 54.61 0)
			(effects
				(font
					(size 1.27 1.27)
					(thickness 0.15)
				)
				(justify left bottom)
				(hide yes)
			)
		)
		(property "Author" "Antmicro"
			(at 208.28 54.61 0)
			(effects
				(font
					(size 1.27 1.27)
					(thickness 0.15)
				)
				(justify left bottom)
				(hide yes)
			)
		)
		(property "Val" "22u"
			(at 185.42 73.6536 90)
			(effects
				(font
					(size 1.27 1.27)
					(thickness 0.15)
				)
				(justify right)
			)
		)
		(property "Voltage" ""
			(at 210.82 54.61 0)
			(effects
				(font
					(size 1.27 1.27)
				)
				(justify left bottom)
				(hide yes)
			)
		)
		(property "Dielectric" ""
			(at 213.36 54.61 0)
			(effects
				(font
					(size 1.27 1.27)
				)
				(justify left bottom)
				(hide yes)
			)
		)
		(property "Public" ""
			(at 215.9 54.61 0)
			(effects
				(font
					(size 1.27 1.27)
				)
				(justify left bottom)
				(hide yes)
			)
		)
		(pin "2"
		)
		(pin "1"
		)
		(instances
			(project "polarfire-som"
				(path ""
					(reference "C87")
					(unit 1)
				)
			)
		)
	)
	(symbol
		(lib_id "antmicroResistors0402:R_20k_0402")
		(at 20.32 236.22 90)
		(unit 1)
		(exclude_from_sim no)
		(in_bom yes)
		(on_board yes)
		(dnp no)
		(fields_autoplaced yes)
		(property "Reference" "R3"
			(at 22.86 232.4099 90)
			(effects
				(font
					(size 1.27 1.27)
					(thickness 0.15)
				)
				(justify right)
			)
		)
		(property "Value" "R_20k_0402"
			(at 33.02 215.9 0)
			(effects
				(font
					(size 1.27 1.27)
					(thickness 0.15)
				)
				(justify left bottom)
				(hide yes)
			)
		)
		(property "Footprint" "antmicro-footprints:R_0402_1005Metric"
			(at 35.56 215.9 0)
			(effects
				(font
					(size 1.27 1.27)
					(thickness 0.15)
				)
				(justify left bottom)
				(hide yes)
			)
		)
		(property "Datasheet" "https://www.bourns.com/docs/product-datasheets/cr.pdf"
			(at 38.1 215.9 0)
			(effects
				(font
					(size 1.27 1.27)
					(thickness 0.15)
				)
				(justify left bottom)
				(hide yes)
			)
		)
		(property "Description" "SMD Chip Resistor, 20 kohm, ± 1%, 62.5 mW, 0402 [1005 Metric], Thick Film, General Purpose"
			(at 20.32 236.22 0)
			(effects
				(font
					(size 1.27 1.27)
				)
				(hide yes)
			)
		)
		(property "MPN" "CR0402-FX-2002GLF"
			(at 40.64 215.9 0)
			(effects
				(font
					(size 1.27 1.27)
					(thickness 0.15)
				)
				(justify left bottom)
				(hide yes)
			)
		)
		(property "Manufacturer" "Bourns"
			(at 43.18 215.9 0)
			(effects
				(font
					(size 1.27 1.27)
					(thickness 0.15)
				)
				(justify left bottom)
				(hide yes)
			)
		)
		(property "License" "Apache-2.0"
			(at 45.72 215.9 0)
			(effects
				(font
					(size 1.27 1.27)
					(thickness 0.15)
				)
				(justify left bottom)
				(hide yes)
			)
		)
		(property "Author" "Antmicro"
			(at 48.26 215.9 0)
			(effects
				(font
					(size 1.27 1.27)
					(thickness 0.15)
				)
				(justify left bottom)
				(hide yes)
			)
		)
		(property "Val" "20k"
			(at 22.86 234.9499 90)
			(effects
				(font
					(size 1.27 1.27)
					(thickness 0.15)
				)
				(justify right)
			)
		)
		(property "Tolerance" "1%"
			(at 30.48 215.9 0)
			(effects
				(font
					(size 1.27 1.27)
				)
				(justify left bottom)
				(hide yes)
			)
		)
		(property "Public" ""
			(at 50.8 215.9 0)
			(effects
				(font
					(size 1.27 1.27)
				)
				(justify left bottom)
				(hide yes)
			)
		)
		(pin "1"
		)
		(pin "2"
		)
		(instances
			(project "polarfire-som"
				(path ""
					(reference "R3")
					(unit 1)
				)
			)
		)
	)
	(symbol
		(lib_id "antmicroResistors0402:R_0R_0402")
		(at 88.9 203.2 90)
		(unit 1)
		(exclude_from_sim no)
		(in_bom yes)
		(on_board yes)
		(dnp no)
		(fields_autoplaced yes)
		(property "Reference" "R8"
			(at 90.805 199.3899 90)
			(effects
				(font
					(size 1.27 1.27)
					(thickness 0.15)
				)
				(justify right)
			)
		)
		(property "Value" "R_0R_0402"
			(at 101.6 182.88 0)
			(effects
				(font
					(size 1.27 1.27)
					(thickness 0.15)
				)
				(justify left bottom)
				(hide yes)
			)
		)
		(property "Footprint" "antmicro-footprints:R_0402_1005Metric"
			(at 104.14 182.88 0)
			(effects
				(font
					(size 1.27 1.27)
					(thickness 0.15)
				)
				(justify left bottom)
				(hide yes)
			)
		)
		(property "Datasheet" "https://industrial.panasonic.com/cdbs/www-data/pdf/RDA0000/AOA0000C301.pdf"
			(at 106.68 182.88 0)
			(effects
				(font
					(size 1.27 1.27)
					(thickness 0.15)
				)
				(justify left bottom)
				(hide yes)
			)
		)
		(property "Description" "SMD Chip Resistor, Jumper, 0 ohm, 100 mW, 0402 [1005 Metric], Thick Film, General Purpose"
			(at 88.9 203.2 0)
			(effects
				(font
					(size 1.27 1.27)
				)
				(hide yes)
			)
		)
		(property "MPN" "ERJ2GE0R00X"
			(at 109.22 182.88 0)
			(effects
				(font
					(size 1.27 1.27)
					(thickness 0.15)
				)
				(justify left bottom)
				(hide yes)
			)
		)
		(property "Manufacturer" "Panasonic"
			(at 111.76 182.88 0)
			(effects
				(font
					(size 1.27 1.27)
					(thickness 0.15)
				)
				(justify left bottom)
				(hide yes)
			)
		)
		(property "License" "Apache-2.0"
			(at 114.3 182.88 0)
			(effects
				(font
					(size 1.27 1.27)
					(thickness 0.15)
				)
				(justify left bottom)
				(hide yes)
			)
		)
		(property "Author" "Antmicro"
			(at 116.84 182.88 0)
			(effects
				(font
					(size 1.27 1.27)
					(thickness 0.15)
				)
				(justify left bottom)
				(hide yes)
			)
		)
		(property "Val" "0R"
			(at 90.805 201.9299 90)
			(effects
				(font
					(size 1.27 1.27)
					(thickness 0.15)
				)
				(justify right)
			)
		)
		(property "Tolerance" "~"
			(at 99.06 182.88 0)
			(effects
				(font
					(size 1.27 1.27)
				)
				(justify left bottom)
				(hide yes)
			)
		)
		(property "Current" "1A"
			(at 119.38 182.88 0)
			(effects
				(font
					(size 1.27 1.27)
					(thickness 0.15)
				)
				(justify left bottom)
				(hide yes)
			)
		)
		(property "Public" ""
			(at 119.38 182.88 0)
			(effects
				(font
					(size 1.27 1.27)
				)
				(justify left bottom)
				(hide yes)
			)
		)
		(pin "1"
		)
		(pin "2"
		)
		(instances
			(project "polarfire-som"
				(path ""
					(reference "R8")
					(unit 1)
				)
			)
		)
	)
	(symbol
		(lib_id "antmicroCapacitors0402:C_22u_0402")
		(at 261.62 116.84 90)
		(unit 1)
		(exclude_from_sim no)
		(in_bom yes)
		(on_board yes)
		(dnp no)
		(fields_autoplaced yes)
		(property "Reference" "C103"
			(at 264.16 113.0236 90)
			(effects
				(font
					(size 1.27 1.27)
					(thickness 0.15)
				)
				(justify right)
			)
		)
		(property "Value" "C_22u_0402"
			(at 271.78 96.52 0)
			(effects
				(font
					(size 1.27 1.27)
					(thickness 0.15)
				)
				(justify left bottom)
				(hide yes)
			)
		)
		(property "Footprint" "antmicro-footprints:C_0402_1005Metric"
			(at 274.32 96.52 0)
			(effects
				(font
					(size 1.27 1.27)
					(thickness 0.15)
				)
				(justify left bottom)
				(hide yes)
			)
		)
		(property "Datasheet" "https://www.murata.com/products/productdetail?partno=GRM158R60J226ME01%23"
			(at 276.86 96.52 0)
			(effects
				(font
					(size 1.27 1.27)
					(thickness 0.15)
				)
				(justify left bottom)
				(hide yes)
			)
		)
		(property "Description" "SMD Multilayer Ceramic Capacitor, 22 uF, 4 V, 0402 [1005 Metric], X6S"
			(at 261.62 116.84 0)
			(effects
				(font
					(size 1.27 1.27)
				)
				(hide yes)
			)
		)
		(property "MPN" "GRM158R60J226ME01D"
			(at 279.4 96.52 0)
			(effects
				(font
					(size 1.27 1.27)
					(thickness 0.15)
				)
				(justify left bottom)
				(hide yes)
			)
		)
		(property "Manufacturer" "Murata"
			(at 281.94 96.52 0)
			(effects
				(font
					(size 1.27 1.27)
					(thickness 0.15)
				)
				(justify left bottom)
				(hide yes)
			)
		)
		(property "License" "Apache-2.0"
			(at 284.48 96.52 0)
			(effects
				(font
					(size 1.27 1.27)
					(thickness 0.15)
				)
				(justify left bottom)
				(hide yes)
			)
		)
		(property "Author" "Antmicro"
			(at 287.02 96.52 0)
			(effects
				(font
					(size 1.27 1.27)
					(thickness 0.15)
				)
				(justify left bottom)
				(hide yes)
			)
		)
		(property "Val" "22u"
			(at 264.16 115.5636 90)
			(effects
				(font
					(size 1.27 1.27)
					(thickness 0.15)
				)
				(justify right)
			)
		)
		(property "Voltage" ""
			(at 289.56 96.52 0)
			(effects
				(font
					(size 1.27 1.27)
				)
				(justify left bottom)
				(hide yes)
			)
		)
		(property "Dielectric" ""
			(at 292.1 96.52 0)
			(effects
				(font
					(size 1.27 1.27)
				)
				(justify left bottom)
				(hide yes)
			)
		)
		(property "Public" ""
			(at 294.64 96.52 0)
			(effects
				(font
					(size 1.27 1.27)
				)
				(justify left bottom)
				(hide yes)
			)
		)
		(pin "2"
		)
		(pin "1"
		)
		(instances
			(project "polarfire-som"
				(path ""
					(reference "C103")
					(unit 1)
				)
			)
		)
	)
	(symbol
		(lib_id "antmicroCapacitors0402:C_100n_0402")
		(at 195.58 99.06 90)
		(unit 1)
		(exclude_from_sim no)
		(in_bom yes)
		(on_board yes)
		(dnp no)
		(property "Reference" "C92"
			(at 198.12 95.25 90)
			(effects
				(font
					(size 1.27 1.27)
					(thickness 0.15)
				)
				(justify right)
			)
		)
		(property "Value" "C_100n_0402"
			(at 205.74 78.74 0)
			(effects
				(font
					(size 1.27 1.27)
					(thickness 0.15)
				)
				(justify left bottom)
				(hide yes)
			)
		)
		(property "Footprint" "antmicro-footprints:C_0402_1005Metric"
			(at 208.28 78.74 0)
			(effects
				(font
					(size 1.27 1.27)
					(thickness 0.15)
				)
				(justify left bottom)
				(hide yes)
			)
		)
		(property "Datasheet" "https://www.murata.com/products/productdetail?partno=GRM155R61H104KE14%23"
			(at 210.82 78.74 0)
			(effects
				(font
					(size 1.27 1.27)
					(thickness 0.15)
				)
				(justify left bottom)
				(hide yes)
			)
		)
		(property "Description" "SMD Multilayer Ceramic Capacitor, 0.1 µF, 50 V, 0402 [1005 Metric], ± 10%, X5R, GRM Series"
			(at 195.58 99.06 0)
			(effects
				(font
					(size 1.27 1.27)
				)
				(hide yes)
			)
		)
		(property "MPN" "GRM155R61H104KE14D"
			(at 213.36 78.74 0)
			(effects
				(font
					(size 1.27 1.27)
					(thickness 0.15)
				)
				(justify left bottom)
				(hide yes)
			)
		)
		(property "Manufacturer" "Murata"
			(at 215.9 78.74 0)
			(effects
				(font
					(size 1.27 1.27)
					(thickness 0.15)
				)
				(justify left bottom)
				(hide yes)
			)
		)
		(property "License" "Apache-2.0"
			(at 218.44 78.74 0)
			(effects
				(font
					(size 1.27 1.27)
					(thickness 0.15)
				)
				(justify left bottom)
				(hide yes)
			)
		)
		(property "Author" "Antmicro"
			(at 220.98 78.74 0)
			(effects
				(font
					(size 1.27 1.27)
					(thickness 0.15)
				)
				(justify left bottom)
				(hide yes)
			)
		)
		(property "Val" "100n"
			(at 198.12 97.79 90)
			(effects
				(font
					(size 1.27 1.27)
					(thickness 0.15)
				)
				(justify right)
			)
		)
		(property "Voltage" "50V"
			(at 223.52 78.74 0)
			(effects
				(font
					(size 1.27 1.27)
				)
				(justify left bottom)
				(hide yes)
			)
		)
		(property "Dielectric" "X5R"
			(at 226.06 78.74 0)
			(effects
				(font
					(size 1.27 1.27)
				)
				(justify left bottom)
				(hide yes)
			)
		)
		(property "Public" ""
			(at 228.6 78.74 0)
			(effects
				(font
					(size 1.27 1.27)
				)
				(justify left bottom)
				(hide yes)
			)
		)
		(pin "1"
		)
		(pin "2"
		)
		(instances
			(project "polarfire-som"
				(path ""
					(reference "C92")
					(unit 1)
				)
			)
		)
	)
)
